FILE_TYPE = MACRO_DRAWING;
SET COLOR_WIRE YELLOW;
SET COLOR_PROP ORANGE;
SET COLOR_DOT WHITE;
SET COLOR_ARC YELLOW;
SET COLOR_BODY GREEN;
SET COLOR_NOTE PURPLE;
SET PROP_DISPLAY VALUE;
SET PAGE_NUMBER P32;
FORCEADD GENOA_SP5..34
(-7775 3450);
FORCEPROP 1 LAST LOCATION U25
J 0
(-8175 6600);
DISPLAY 0.489362 (-8175 6600);
PAINT SKYBLUE (-8175 6600);
FORCEPROP 0 LAST $SEC 34
J 0
(-8150 6850);
DISPLAY 0.680851 (-8150 6850);
PAINT MONO (-8150 6850);
DISPLAY INVISIBLE (-8150 6850);
FORCEPROP 0 LAST CDS_SEC 34
J 0
(-8175 6725);
DISPLAY 1.021277 (-8175 6725);
DISPLAY INVISIBLE (-8175 6725);
FORCEPROP 0 LASTPIN (-8325 6400) $PN BL26
J 2
(-8335 6410);
DISPLAY 0.489362 (-8335 6410);
PAINT MONO (-8335 6410);
FORCEPROP 0 LASTPIN (-8325 6350) $PN BL28
J 2
(-8335 6360);
DISPLAY 0.489362 (-8335 6360);
PAINT MONO (-8335 6360);
FORCEPROP 0 LASTPIN (-8325 6300) $PN BL49
J 2
(-8335 6310);
DISPLAY 0.489362 (-8335 6310);
PAINT MONO (-8335 6310);
FORCEPROP 0 LASTPIN (-8325 6250) $PN BL51
J 2
(-8335 6260);
DISPLAY 0.489362 (-8335 6260);
PAINT MONO (-8335 6260);
FORCEPROP 0 LASTPIN (-8325 6200) $PN BL53
J 2
(-8335 6210);
DISPLAY 0.489362 (-8335 6210);
PAINT MONO (-8335 6210);
FORCEPROP 0 LASTPIN (-8325 6150) $PN BL56
J 2
(-8335 6160);
DISPLAY 0.489362 (-8335 6160);
PAINT MONO (-8335 6160);
FORCEPROP 0 LASTPIN (-8325 6100) $PN BL58
J 2
(-8335 6110);
DISPLAY 0.489362 (-8335 6110);
PAINT MONO (-8335 6110);
FORCEPROP 0 LASTPIN (-8325 6050) $PN BL61
J 2
(-8335 6060);
DISPLAY 0.489362 (-8335 6060);
PAINT MONO (-8335 6060);
FORCEPROP 0 LASTPIN (-8325 6000) $PN BL63
J 2
(-8335 6010);
DISPLAY 0.489362 (-8335 6010);
PAINT MONO (-8335 6010);
FORCEPROP 0 LASTPIN (-8325 5950) $PN BL65
J 2
(-8335 5960);
DISPLAY 0.489362 (-8335 5960);
PAINT MONO (-8335 5960);
FORCEPROP 0 LASTPIN (-8325 5900) $PN BL68
J 2
(-8335 5910);
DISPLAY 0.489362 (-8335 5910);
PAINT MONO (-8335 5910);
FORCEPROP 0 LASTPIN (-8325 5850) $PN BL70
J 2
(-8335 5860);
DISPLAY 0.489362 (-8335 5860);
PAINT MONO (-8335 5860);
FORCEPROP 0 LASTPIN (-8325 5800) $PN BL72
J 2
(-8335 5810);
DISPLAY 0.489362 (-8335 5810);
PAINT MONO (-8335 5810);
FORCEPROP 0 LASTPIN (-8325 5750) $PN BL75
J 2
(-8335 5760);
DISPLAY 0.489362 (-8335 5760);
PAINT MONO (-8335 5760);
FORCEPROP 0 LASTPIN (-8325 5700) $PN BM3
J 2
(-8335 5710);
DISPLAY 0.489362 (-8335 5710);
PAINT MONO (-8335 5710);
FORCEPROP 0 LASTPIN (-8325 5650) $PN BM8
J 2
(-8335 5660);
DISPLAY 0.489362 (-8335 5660);
PAINT MONO (-8335 5660);
FORCEPROP 0 LASTPIN (-8325 5600) $PN BM10
J 2
(-8335 5610);
DISPLAY 0.489362 (-8335 5610);
PAINT MONO (-8335 5610);
FORCEPROP 0 LASTPIN (-8325 5550) $PN BM15
J 2
(-8335 5560);
DISPLAY 0.489362 (-8335 5560);
PAINT MONO (-8335 5560);
FORCEPROP 0 LASTPIN (-8325 5500) $PN BM17
J 2
(-8335 5510);
DISPLAY 0.489362 (-8335 5510);
PAINT MONO (-8335 5510);
FORCEPROP 0 LASTPIN (-8325 5450) $PN BM23
J 2
(-8335 5460);
DISPLAY 0.489362 (-8335 5460);
PAINT MONO (-8335 5460);
FORCEPROP 0 LASTPIN (-8325 5400) $PN BM25
J 2
(-8335 5410);
DISPLAY 0.489362 (-8335 5410);
PAINT MONO (-8335 5410);
FORCEPROP 0 LASTPIN (-8325 5350) $PN BM27
J 2
(-8335 5360);
DISPLAY 0.489362 (-8335 5360);
PAINT MONO (-8335 5360);
FORCEPROP 0 LASTPIN (-8325 5300) $PN BM29
J 2
(-8335 5310);
DISPLAY 0.489362 (-8335 5310);
PAINT MONO (-8335 5310);
FORCEPROP 0 LASTPIN (-8325 5250) $PN BM31
J 2
(-8335 5260);
DISPLAY 0.489362 (-8335 5260);
PAINT MONO (-8335 5260);
FORCEPROP 0 LASTPIN (-8325 5200) $PN BM33
J 2
(-8335 5210);
DISPLAY 0.489362 (-8335 5210);
PAINT MONO (-8335 5210);
FORCEPROP 0 LASTPIN (-8325 5150) $PN BM35
J 2
(-8335 5160);
DISPLAY 0.489362 (-8335 5160);
PAINT MONO (-8335 5160);
FORCEPROP 0 LASTPIN (-8325 5100) $PN BM37
J 2
(-8335 5110);
DISPLAY 0.489362 (-8335 5110);
PAINT MONO (-8335 5110);
FORCEPROP 0 LASTPIN (-8325 5050) $PN BM40
J 2
(-8335 5060);
DISPLAY 0.489362 (-8335 5060);
PAINT MONO (-8335 5060);
FORCEPROP 0 LASTPIN (-8325 5000) $PN BM42
J 2
(-8335 5010);
DISPLAY 0.489362 (-8335 5010);
PAINT MONO (-8335 5010);
FORCEPROP 0 LASTPIN (-8325 4950) $PN BM44
J 2
(-8335 4960);
DISPLAY 0.489362 (-8335 4960);
PAINT MONO (-8335 4960);
FORCEPROP 0 LASTPIN (-8325 4900) $PN BM46
J 2
(-8335 4910);
DISPLAY 0.489362 (-8335 4910);
PAINT MONO (-8335 4910);
FORCEPROP 0 LASTPIN (-8325 4850) $PN BM48
J 2
(-8335 4860);
DISPLAY 0.489362 (-8335 4860);
PAINT MONO (-8335 4860);
FORCEPROP 0 LASTPIN (-8325 4800) $PN BM50
J 2
(-8335 4810);
DISPLAY 0.489362 (-8335 4810);
PAINT MONO (-8335 4810);
FORCEPROP 0 LASTPIN (-8325 4750) $PN BM52
J 2
(-8335 4760);
DISPLAY 0.489362 (-8335 4760);
PAINT MONO (-8335 4760);
FORCEPROP 0 LASTPIN (-8325 4700) $PN BM54
J 2
(-8335 4710);
DISPLAY 0.489362 (-8335 4710);
PAINT MONO (-8335 4710);
FORCEPROP 0 LASTPIN (-8325 4650) $PN BM59
J 2
(-8335 4660);
DISPLAY 0.489362 (-8335 4660);
PAINT MONO (-8335 4660);
FORCEPROP 0 LASTPIN (-8325 4600) $PN BM61
J 2
(-8335 4610);
DISPLAY 0.489362 (-8335 4610);
PAINT MONO (-8335 4610);
FORCEPROP 0 LASTPIN (-8325 4550) $PN BM66
J 2
(-8335 4560);
DISPLAY 0.489362 (-8335 4560);
PAINT MONO (-8335 4560);
FORCEPROP 0 LASTPIN (-8325 4500) $PN BM68
J 2
(-8335 4510);
DISPLAY 0.489362 (-8335 4510);
PAINT MONO (-8335 4510);
FORCEPROP 0 LASTPIN (-8325 4450) $PN BM73
J 2
(-8335 4460);
DISPLAY 0.489362 (-8335 4460);
PAINT MONO (-8335 4460);
FORCEPROP 0 LASTPIN (-8325 4400) $PN BN1
J 2
(-8335 4410);
DISPLAY 0.489362 (-8335 4410);
PAINT MONO (-8335 4410);
FORCEPROP 0 LASTPIN (-8325 4350) $PN BN4
J 2
(-8335 4360);
DISPLAY 0.489362 (-8335 4360);
PAINT MONO (-8335 4360);
FORCEPROP 0 LASTPIN (-8325 4300) $PN BN6
J 2
(-8335 4310);
DISPLAY 0.489362 (-8335 4310);
PAINT MONO (-8335 4310);
FORCEPROP 0 LASTPIN (-8325 4250) $PN BN8
J 2
(-8335 4260);
DISPLAY 0.489362 (-8335 4260);
PAINT MONO (-8335 4260);
FORCEPROP 0 LASTPIN (-8325 4200) $PN BN11
J 2
(-8335 4210);
DISPLAY 0.489362 (-8335 4210);
PAINT MONO (-8335 4210);
FORCEPROP 0 LASTPIN (-8325 4150) $PN BN13
J 2
(-8335 4160);
DISPLAY 0.489362 (-8335 4160);
PAINT MONO (-8335 4160);
FORCEPROP 0 LASTPIN (-8325 4100) $PN BN15
J 2
(-8335 4110);
DISPLAY 0.489362 (-8335 4110);
PAINT MONO (-8335 4110);
FORCEPROP 0 LASTPIN (-8325 4050) $PN BN18
J 2
(-8335 4060);
DISPLAY 0.489362 (-8335 4060);
PAINT MONO (-8335 4060);
FORCEPROP 0 LASTPIN (-8325 4000) $PN BN20
J 2
(-8335 4010);
DISPLAY 0.489362 (-8335 4010);
PAINT MONO (-8335 4010);
FORCEPROP 0 LASTPIN (-8325 3950) $PN BN22
J 2
(-8335 3960);
DISPLAY 0.489362 (-8335 3960);
PAINT MONO (-8335 3960);
FORCEPROP 0 LASTPIN (-8325 3900) $PN BN24
J 2
(-8335 3910);
DISPLAY 0.489362 (-8335 3910);
PAINT MONO (-8335 3910);
FORCEPROP 0 LASTPIN (-8325 3850) $PN BN26
J 2
(-8335 3860);
DISPLAY 0.489362 (-8335 3860);
PAINT MONO (-8335 3860);
FORCEPROP 0 LASTPIN (-8325 3800) $PN BN28
J 2
(-8335 3810);
DISPLAY 0.489362 (-8335 3810);
PAINT MONO (-8335 3810);
FORCEPROP 0 LASTPIN (-8325 3750) $PN BN30
J 2
(-8335 3760);
DISPLAY 0.489362 (-8335 3760);
PAINT MONO (-8335 3760);
FORCEPROP 0 LASTPIN (-8325 3700) $PN BN32
J 2
(-8335 3710);
DISPLAY 0.489362 (-8335 3710);
PAINT MONO (-8335 3710);
FORCEPROP 0 LASTPIN (-8325 3650) $PN BN34
J 2
(-8335 3660);
DISPLAY 0.489362 (-8335 3660);
PAINT MONO (-8335 3660);
FORCEPROP 0 LASTPIN (-8325 3600) $PN BN36
J 2
(-8335 3610);
DISPLAY 0.489362 (-8335 3610);
PAINT MONO (-8335 3610);
FORCEPROP 0 LASTPIN (-8325 3550) $PN BN41
J 2
(-8335 3560);
DISPLAY 0.489362 (-8335 3560);
PAINT MONO (-8335 3560);
FORCEPROP 0 LASTPIN (-8325 3500) $PN BN43
J 2
(-8335 3510);
DISPLAY 0.489362 (-8335 3510);
PAINT MONO (-8335 3510);
FORCEPROP 0 LASTPIN (-8325 3450) $PN BN45
J 2
(-8335 3460);
DISPLAY 0.489362 (-8335 3460);
PAINT MONO (-8335 3460);
FORCEPROP 0 LASTPIN (-8325 3400) $PN BN47
J 2
(-8335 3410);
DISPLAY 0.489362 (-8335 3410);
PAINT MONO (-8335 3410);
FORCEPROP 0 LASTPIN (-8325 3350) $PN BN49
J 2
(-8335 3360);
DISPLAY 0.489362 (-8335 3360);
PAINT MONO (-8335 3360);
FORCEPROP 0 LASTPIN (-8325 3300) $PN BN51
J 2
(-8335 3310);
DISPLAY 0.489362 (-8335 3310);
PAINT MONO (-8335 3310);
FORCEPROP 0 LASTPIN (-8325 3250) $PN BN53
J 2
(-8335 3260);
DISPLAY 0.489362 (-8335 3260);
PAINT MONO (-8335 3260);
FORCEPROP 0 LASTPIN (-8325 3200) $PN BN56
J 2
(-8335 3210);
DISPLAY 0.489362 (-8335 3210);
PAINT MONO (-8335 3210);
FORCEPROP 0 LASTPIN (-8325 3150) $PN BN58
J 2
(-8335 3160);
DISPLAY 0.489362 (-8335 3160);
PAINT MONO (-8335 3160);
FORCEPROP 0 LASTPIN (-8325 3100) $PN BN61
J 2
(-8335 3110);
DISPLAY 0.489362 (-8335 3110);
PAINT MONO (-8335 3110);
FORCEPROP 0 LASTPIN (-8325 3050) $PN BN63
J 2
(-8335 3060);
DISPLAY 0.489362 (-8335 3060);
PAINT MONO (-8335 3060);
FORCEPROP 0 LASTPIN (-8325 3000) $PN BN65
J 2
(-8335 3010);
DISPLAY 0.489362 (-8335 3010);
PAINT MONO (-8335 3010);
FORCEPROP 0 LASTPIN (-8325 2950) $PN BN68
J 2
(-8335 2960);
DISPLAY 0.489362 (-8335 2960);
PAINT MONO (-8335 2960);
FORCEPROP 0 LASTPIN (-8325 2900) $PN BN70
J 2
(-8335 2910);
DISPLAY 0.489362 (-8335 2910);
PAINT MONO (-8335 2910);
FORCEPROP 0 LASTPIN (-8325 2850) $PN BN72
J 2
(-8335 2860);
DISPLAY 0.489362 (-8335 2860);
PAINT MONO (-8335 2860);
FORCEPROP 0 LASTPIN (-8325 2800) $PN BN75
J 2
(-8335 2810);
DISPLAY 0.489362 (-8335 2810);
PAINT MONO (-8335 2810);
FORCEPROP 0 LASTPIN (-8325 2750) $PN BP3
J 2
(-8335 2760);
DISPLAY 0.489362 (-8335 2760);
PAINT MONO (-8335 2760);
FORCEPROP 0 LASTPIN (-8325 2700) $PN BP5
J 2
(-8335 2710);
DISPLAY 0.489362 (-8335 2710);
PAINT MONO (-8335 2710);
FORCEPROP 0 LASTPIN (-8325 2650) $PN BP8
J 2
(-8335 2660);
DISPLAY 0.489362 (-8335 2660);
PAINT MONO (-8335 2660);
FORCEPROP 0 LASTPIN (-8325 2600) $PN BP10
J 2
(-8335 2610);
DISPLAY 0.489362 (-8335 2610);
PAINT MONO (-8335 2610);
FORCEPROP 0 LASTPIN (-8325 2550) $PN BP12
J 2
(-8335 2560);
DISPLAY 0.489362 (-8335 2560);
PAINT MONO (-8335 2560);
FORCEPROP 0 LASTPIN (-8325 2500) $PN BP15
J 2
(-8335 2510);
DISPLAY 0.489362 (-8335 2510);
PAINT MONO (-8335 2510);
FORCEPROP 0 LASTPIN (-8325 2450) $PN BP17
J 2
(-8335 2460);
DISPLAY 0.489362 (-8335 2460);
PAINT MONO (-8335 2460);
FORCEPROP 0 LASTPIN (-8325 2400) $PN BP19
J 2
(-8335 2410);
DISPLAY 0.489362 (-8335 2410);
PAINT MONO (-8335 2410);
FORCEPROP 0 LASTPIN (-8325 2350) $PN BP23
J 2
(-8335 2360);
DISPLAY 0.489362 (-8335 2360);
PAINT MONO (-8335 2360);
FORCEPROP 0 LASTPIN (-8325 2300) $PN BP25
J 2
(-8335 2310);
DISPLAY 0.489362 (-8335 2310);
PAINT MONO (-8335 2310);
FORCEPROP 0 LASTPIN (-8325 2250) $PN BP27
J 2
(-8335 2260);
DISPLAY 0.489362 (-8335 2260);
PAINT MONO (-8335 2260);
FORCEPROP 0 LASTPIN (-8325 2200) $PN BP29
J 2
(-8335 2210);
DISPLAY 0.489362 (-8335 2210);
PAINT MONO (-8335 2210);
FORCEPROP 0 LASTPIN (-8325 2150) $PN BP31
J 2
(-8335 2160);
DISPLAY 0.489362 (-8335 2160);
PAINT MONO (-8335 2160);
FORCEPROP 0 LASTPIN (-8325 2100) $PN BP33
J 2
(-8335 2110);
DISPLAY 0.489362 (-8335 2110);
PAINT MONO (-8335 2110);
FORCEPROP 0 LASTPIN (-8325 2050) $PN BP35
J 2
(-8335 2060);
DISPLAY 0.489362 (-8335 2060);
PAINT MONO (-8335 2060);
FORCEPROP 0 LASTPIN (-8325 2000) $PN BP37
J 2
(-8335 2010);
DISPLAY 0.489362 (-8335 2010);
PAINT MONO (-8335 2010);
FORCEPROP 0 LASTPIN (-8325 1950) $PN BP40
J 2
(-8335 1960);
DISPLAY 0.489362 (-8335 1960);
PAINT MONO (-8335 1960);
FORCEPROP 0 LASTPIN (-8325 1900) $PN BP42
J 2
(-8335 1910);
DISPLAY 0.489362 (-8335 1910);
PAINT MONO (-8335 1910);
FORCEPROP 0 LASTPIN (-8325 1850) $PN BP44
J 2
(-8335 1860);
DISPLAY 0.489362 (-8335 1860);
PAINT MONO (-8335 1860);
FORCEPROP 0 LASTPIN (-8325 1800) $PN BP46
J 2
(-8335 1810);
DISPLAY 0.489362 (-8335 1810);
PAINT MONO (-8335 1810);
FORCEPROP 0 LASTPIN (-8325 1750) $PN BP48
J 2
(-8335 1760);
DISPLAY 0.489362 (-8335 1760);
PAINT MONO (-8335 1760);
FORCEPROP 0 LASTPIN (-8325 1700) $PN BP50
J 2
(-8335 1710);
DISPLAY 0.489362 (-8335 1710);
PAINT MONO (-8335 1710);
FORCEPROP 0 LASTPIN (-8325 1650) $PN BP52
J 2
(-8335 1660);
DISPLAY 0.489362 (-8335 1660);
PAINT MONO (-8335 1660);
FORCEPROP 0 LASTPIN (-8325 1600) $PN BP54
J 2
(-8335 1610);
DISPLAY 0.489362 (-8335 1610);
PAINT MONO (-8335 1610);
FORCEPROP 0 LASTPIN (-8325 1550) $PN BP57
J 2
(-8335 1560);
DISPLAY 0.489362 (-8335 1560);
PAINT MONO (-8335 1560);
FORCEPROP 0 LASTPIN (-8325 1500) $PN BP59
J 2
(-8335 1510);
DISPLAY 0.489362 (-8335 1510);
PAINT MONO (-8335 1510);
FORCEPROP 0 LASTPIN (-8325 1450) $PN BP61
J 2
(-8335 1460);
DISPLAY 0.489362 (-8335 1460);
PAINT MONO (-8335 1460);
FORCEPROP 0 LASTPIN (-8325 1400) $PN BP64
J 2
(-8335 1410);
DISPLAY 0.489362 (-8335 1410);
PAINT MONO (-8335 1410);
FORCEPROP 0 LASTPIN (-8325 1350) $PN BP66
J 2
(-8335 1360);
DISPLAY 0.489362 (-8335 1360);
PAINT MONO (-8335 1360);
FORCEPROP 0 LASTPIN (-8325 1300) $PN BP68
J 2
(-8335 1310);
DISPLAY 0.489362 (-8335 1310);
PAINT MONO (-8335 1310);
FORCEPROP 0 LASTPIN (-8325 1250) $PN BP71
J 2
(-8335 1260);
DISPLAY 0.489362 (-8335 1260);
PAINT MONO (-8335 1260);
FORCEPROP 0 LASTPIN (-8325 1200) $PN BP73
J 2
(-8335 1210);
DISPLAY 0.489362 (-8335 1210);
PAINT MONO (-8335 1210);
FORCEPROP 0 LASTPIN (-8325 1150) $PN BR1
J 2
(-8335 1160);
DISPLAY 0.489362 (-8335 1160);
PAINT MONO (-8335 1160);
FORCEPROP 0 LASTPIN (-8325 1100) $PN BR3
J 2
(-8335 1110);
DISPLAY 0.489362 (-8335 1110);
PAINT MONO (-8335 1110);
FORCEPROP 0 LASTPIN (-8325 1050) $PN BR6
J 2
(-8335 1060);
DISPLAY 0.489362 (-8335 1060);
PAINT MONO (-8335 1060);
FORCEPROP 0 LASTPIN (-8325 1000) $PN BR7
J 2
(-8335 1010);
DISPLAY 0.489362 (-8335 1010);
PAINT MONO (-8335 1010);
FORCEPROP 0 LASTPIN (-8325 950) $PN BR8
J 2
(-8335 960);
DISPLAY 0.489362 (-8335 960);
PAINT MONO (-8335 960);
FORCEPROP 0 LASTPIN (-8325 900) $PN BR10
J 2
(-8335 910);
DISPLAY 0.489362 (-8335 910);
PAINT MONO (-8335 910);
FORCEPROP 0 LASTPIN (-8325 850) $PN BR13
J 2
(-8335 860);
DISPLAY 0.489362 (-8335 860);
PAINT MONO (-8335 860);
FORCEPROP 0 LASTPIN (-8325 800) $PN BR14
J 2
(-8335 810);
DISPLAY 0.489362 (-8335 810);
PAINT MONO (-8335 810);
FORCEPROP 0 LASTPIN (-8325 750) $PN BR15
J 2
(-8335 760);
DISPLAY 0.489362 (-8335 760);
PAINT MONO (-8335 760);
FORCEPROP 0 LASTPIN (-8325 700) $PN BR17
J 2
(-8335 710);
DISPLAY 0.489362 (-8335 710);
PAINT MONO (-8335 710);
FORCEPROP 0 LASTPIN (-8325 650) $PN BR20
J 2
(-8335 660);
DISPLAY 0.489362 (-8335 660);
PAINT MONO (-8335 660);
FORCEPROP 0 LASTPIN (-8325 600) $PN BR21
J 2
(-8335 610);
DISPLAY 0.489362 (-8335 610);
PAINT MONO (-8335 610);
FORCEPROP 0 LASTPIN (-8325 550) $PN BR22
J 2
(-8335 560);
DISPLAY 0.489362 (-8335 560);
PAINT MONO (-8335 560);
FORCEPROP 0 LASTPIN (-8325 500) $PN BR24
J 2
(-8335 510);
DISPLAY 0.489362 (-8335 510);
PAINT MONO (-8335 510);
FORCEPROP 0 LASTPIN (-7225 6400) $PN BR26
J 0
(-7215 6410);
DISPLAY 0.489362 (-7215 6410);
PAINT MONO (-7215 6410);
FORCEPROP 0 LASTPIN (-7225 6350) $PN BR28
J 0
(-7215 6360);
DISPLAY 0.489362 (-7215 6360);
PAINT MONO (-7215 6360);
FORCEPROP 0 LASTPIN (-7225 6300) $PN BR30
J 0
(-7215 6310);
DISPLAY 0.489362 (-7215 6310);
PAINT MONO (-7215 6310);
FORCEPROP 0 LASTPIN (-7225 6250) $PN BR32
J 0
(-7215 6260);
DISPLAY 0.489362 (-7215 6260);
PAINT MONO (-7215 6260);
FORCEPROP 0 LASTPIN (-7225 6200) $PN BR34
J 0
(-7215 6210);
DISPLAY 0.489362 (-7215 6210);
PAINT MONO (-7215 6210);
FORCEPROP 0 LASTPIN (-7225 6150) $PN BR36
J 0
(-7215 6160);
DISPLAY 0.489362 (-7215 6160);
PAINT MONO (-7215 6160);
FORCEPROP 0 LASTPIN (-7225 6100) $PN BR41
J 0
(-7215 6110);
DISPLAY 0.489362 (-7215 6110);
PAINT MONO (-7215 6110);
FORCEPROP 0 LASTPIN (-7225 6050) $PN BR43
J 0
(-7215 6060);
DISPLAY 0.489362 (-7215 6060);
PAINT MONO (-7215 6060);
FORCEPROP 0 LASTPIN (-7225 6000) $PN BR45
J 0
(-7215 6010);
DISPLAY 0.489362 (-7215 6010);
PAINT MONO (-7215 6010);
FORCEPROP 0 LASTPIN (-7225 5950) $PN BR47
J 0
(-7215 5960);
DISPLAY 0.489362 (-7215 5960);
PAINT MONO (-7215 5960);
FORCEPROP 0 LASTPIN (-7225 5900) $PN BR49
J 0
(-7215 5910);
DISPLAY 0.489362 (-7215 5910);
PAINT MONO (-7215 5910);
FORCEPROP 0 LASTPIN (-7225 5850) $PN BR51
J 0
(-7215 5860);
DISPLAY 0.489362 (-7215 5860);
PAINT MONO (-7215 5860);
FORCEPROP 0 LASTPIN (-7225 5800) $PN BR55
J 0
(-7215 5810);
DISPLAY 0.489362 (-7215 5810);
PAINT MONO (-7215 5810);
FORCEPROP 0 LASTPIN (-7225 5750) $PN BR56
J 0
(-7215 5760);
DISPLAY 0.489362 (-7215 5760);
PAINT MONO (-7215 5760);
FORCEPROP 0 LASTPIN (-7225 5700) $PN BR59
J 0
(-7215 5710);
DISPLAY 0.489362 (-7215 5710);
PAINT MONO (-7215 5710);
FORCEPROP 0 LASTPIN (-7225 5650) $PN BR61
J 0
(-7215 5660);
DISPLAY 0.489362 (-7215 5660);
PAINT MONO (-7215 5660);
FORCEPROP 0 LASTPIN (-7225 5600) $PN BR62
J 0
(-7215 5610);
DISPLAY 0.489362 (-7215 5610);
PAINT MONO (-7215 5610);
FORCEPROP 0 LASTPIN (-7225 5550) $PN BR63
J 0
(-7215 5560);
DISPLAY 0.489362 (-7215 5560);
PAINT MONO (-7215 5560);
FORCEPROP 0 LASTPIN (-7225 5500) $PN BR66
J 0
(-7215 5510);
DISPLAY 0.489362 (-7215 5510);
PAINT MONO (-7215 5510);
FORCEPROP 0 LASTPIN (-7225 5450) $PN BR68
J 0
(-7215 5460);
DISPLAY 0.489362 (-7215 5460);
PAINT MONO (-7215 5460);
FORCEPROP 0 LASTPIN (-7225 5400) $PN BR69
J 0
(-7215 5410);
DISPLAY 0.489362 (-7215 5410);
PAINT MONO (-7215 5410);
FORCEPROP 0 LASTPIN (-7225 5350) $PN BR70
J 0
(-7215 5360);
DISPLAY 0.489362 (-7215 5360);
PAINT MONO (-7215 5360);
FORCEPROP 0 LASTPIN (-7225 5300) $PN BR73
J 0
(-7215 5310);
DISPLAY 0.489362 (-7215 5310);
PAINT MONO (-7215 5310);
FORCEPROP 0 LASTPIN (-7225 5250) $PN BR75
J 0
(-7215 5260);
DISPLAY 0.489362 (-7215 5260);
PAINT MONO (-7215 5260);
FORCEPROP 0 LASTPIN (-7225 5200) $PN BT3
J 0
(-7215 5210);
DISPLAY 0.489362 (-7215 5210);
PAINT MONO (-7215 5210);
FORCEPROP 0 LASTPIN (-7225 5150) $PN BT4
J 0
(-7215 5160);
DISPLAY 0.489362 (-7215 5160);
PAINT MONO (-7215 5160);
FORCEPROP 0 LASTPIN (-7225 5100) $PN BT5
J 0
(-7215 5110);
DISPLAY 0.489362 (-7215 5110);
PAINT MONO (-7215 5110);
FORCEPROP 0 LASTPIN (-7225 5050) $PN BT7
J 0
(-7215 5060);
DISPLAY 0.489362 (-7215 5060);
PAINT MONO (-7215 5060);
FORCEPROP 0 LASTPIN (-7225 5000) $PN BT8
J 0
(-7215 5010);
DISPLAY 0.489362 (-7215 5010);
PAINT MONO (-7215 5010);
FORCEPROP 0 LASTPIN (-7225 4950) $PN BT10
J 0
(-7215 4960);
DISPLAY 0.489362 (-7215 4960);
PAINT MONO (-7215 4960);
FORCEPROP 0 LASTPIN (-7225 4900) $PN BT11
J 0
(-7215 4910);
DISPLAY 0.489362 (-7215 4910);
PAINT MONO (-7215 4910);
FORCEPROP 0 LASTPIN (-7225 4850) $PN BT12
J 0
(-7215 4860);
DISPLAY 0.489362 (-7215 4860);
PAINT MONO (-7215 4860);
FORCEPROP 0 LASTPIN (-7225 4800) $PN BT14
J 0
(-7215 4810);
DISPLAY 0.489362 (-7215 4810);
PAINT MONO (-7215 4810);
FORCEPROP 0 LASTPIN (-7225 4750) $PN BT15
J 0
(-7215 4760);
DISPLAY 0.489362 (-7215 4760);
PAINT MONO (-7215 4760);
FORCEPROP 0 LASTPIN (-7225 4700) $PN BT17
J 0
(-7215 4710);
DISPLAY 0.489362 (-7215 4710);
PAINT MONO (-7215 4710);
FORCEPROP 0 LASTPIN (-7225 4650) $PN BT18
J 0
(-7215 4660);
DISPLAY 0.489362 (-7215 4660);
PAINT MONO (-7215 4660);
FORCEPROP 0 LASTPIN (-7225 4600) $PN BT19
J 0
(-7215 4610);
DISPLAY 0.489362 (-7215 4610);
PAINT MONO (-7215 4610);
FORCEPROP 0 LASTPIN (-7225 4550) $PN BT21
J 0
(-7215 4560);
DISPLAY 0.489362 (-7215 4560);
PAINT MONO (-7215 4560);
FORCEPROP 0 LASTPIN (-7225 4500) $PN BT22
J 0
(-7215 4510);
DISPLAY 0.489362 (-7215 4510);
PAINT MONO (-7215 4510);
FORCEPROP 0 LASTPIN (-7225 4450) $PN BT25
J 0
(-7215 4460);
DISPLAY 0.489362 (-7215 4460);
PAINT MONO (-7215 4460);
FORCEPROP 0 LASTPIN (-7225 4400) $PN BT28
J 0
(-7215 4410);
DISPLAY 0.489362 (-7215 4410);
PAINT MONO (-7215 4410);
FORCEPROP 0 LASTPIN (-7225 4350) $PN BT31
J 0
(-7215 4360);
DISPLAY 0.489362 (-7215 4360);
PAINT MONO (-7215 4360);
FORCEPROP 0 LASTPIN (-7225 4300) $PN BT34
J 0
(-7215 4310);
DISPLAY 0.489362 (-7215 4310);
PAINT MONO (-7215 4310);
FORCEPROP 0 LASTPIN (-7225 4250) $PN BT37
J 0
(-7215 4260);
DISPLAY 0.489362 (-7215 4260);
PAINT MONO (-7215 4260);
FORCEPROP 0 LASTPIN (-7225 4200) $PN BT39
J 0
(-7215 4210);
DISPLAY 0.489362 (-7215 4210);
PAINT MONO (-7215 4210);
FORCEPROP 0 LASTPIN (-7225 4150) $PN BT42
J 0
(-7215 4160);
DISPLAY 0.489362 (-7215 4160);
PAINT MONO (-7215 4160);
FORCEPROP 0 LASTPIN (-7225 4100) $PN BT45
J 0
(-7215 4110);
DISPLAY 0.489362 (-7215 4110);
PAINT MONO (-7215 4110);
FORCEPROP 0 LASTPIN (-7225 4050) $PN BT48
J 0
(-7215 4060);
DISPLAY 0.489362 (-7215 4060);
PAINT MONO (-7215 4060);
FORCEPROP 0 LASTPIN (-7225 4000) $PN BT51
J 0
(-7215 4010);
DISPLAY 0.489362 (-7215 4010);
PAINT MONO (-7215 4010);
FORCEPROP 0 LASTPIN (-7225 3950) $PN BT54
J 0
(-7215 3960);
DISPLAY 0.489362 (-7215 3960);
PAINT MONO (-7215 3960);
FORCEPROP 0 LASTPIN (-7225 3900) $PN BT55
J 0
(-7215 3910);
DISPLAY 0.489362 (-7215 3910);
PAINT MONO (-7215 3910);
FORCEPROP 0 LASTPIN (-7225 3850) $PN BT57
J 0
(-7215 3860);
DISPLAY 0.489362 (-7215 3860);
PAINT MONO (-7215 3860);
FORCEPROP 0 LASTPIN (-7225 3800) $PN BT58
J 0
(-7215 3810);
DISPLAY 0.489362 (-7215 3810);
PAINT MONO (-7215 3810);
FORCEPROP 0 LASTPIN (-7225 3750) $PN BT59
J 0
(-7215 3760);
DISPLAY 0.489362 (-7215 3760);
PAINT MONO (-7215 3760);
FORCEPROP 0 LASTPIN (-7225 3700) $PN BT61
J 0
(-7215 3710);
DISPLAY 0.489362 (-7215 3710);
PAINT MONO (-7215 3710);
FORCEPROP 0 LASTPIN (-7225 3650) $PN BT62
J 0
(-7215 3660);
DISPLAY 0.489362 (-7215 3660);
PAINT MONO (-7215 3660);
FORCEPROP 0 LASTPIN (-7225 3600) $PN BT64
J 0
(-7215 3610);
DISPLAY 0.489362 (-7215 3610);
PAINT MONO (-7215 3610);
FORCEPROP 0 LASTPIN (-7225 3550) $PN BT65
J 0
(-7215 3560);
DISPLAY 0.489362 (-7215 3560);
PAINT MONO (-7215 3560);
FORCEPROP 0 LASTPIN (-7225 3500) $PN BT66
J 0
(-7215 3510);
DISPLAY 0.489362 (-7215 3510);
PAINT MONO (-7215 3510);
FORCEPROP 0 LASTPIN (-7225 3450) $PN BT68
J 0
(-7215 3460);
DISPLAY 0.489362 (-7215 3460);
PAINT MONO (-7215 3460);
FORCEPROP 0 LASTPIN (-7225 3400) $PN BT69
J 0
(-7215 3410);
DISPLAY 0.489362 (-7215 3410);
PAINT MONO (-7215 3410);
FORCEPROP 0 LASTPIN (-7225 3350) $PN BT71
J 0
(-7215 3360);
DISPLAY 0.489362 (-7215 3360);
PAINT MONO (-7215 3360);
FORCEPROP 0 LASTPIN (-7225 3300) $PN BT72
J 0
(-7215 3310);
DISPLAY 0.489362 (-7215 3310);
PAINT MONO (-7215 3310);
FORCEPROP 0 LASTPIN (-7225 3250) $PN BT73
J 0
(-7215 3260);
DISPLAY 0.489362 (-7215 3260);
PAINT MONO (-7215 3260);
FORCEPROP 0 LASTPIN (-7225 3200) $PN BU1
J 0
(-7215 3210);
DISPLAY 0.489362 (-7215 3210);
PAINT MONO (-7215 3210);
FORCEPROP 0 LASTPIN (-7225 3150) $PN BU4
J 0
(-7215 3160);
DISPLAY 0.489362 (-7215 3160);
PAINT MONO (-7215 3160);
FORCEPROP 0 LASTPIN (-7225 3100) $PN BU6
J 0
(-7215 3110);
DISPLAY 0.489362 (-7215 3110);
PAINT MONO (-7215 3110);
FORCEPROP 0 LASTPIN (-7225 3050) $PN BU8
J 0
(-7215 3060);
DISPLAY 0.489362 (-7215 3060);
PAINT MONO (-7215 3060);
FORCEPROP 0 LASTPIN (-7225 3000) $PN BU11
J 0
(-7215 3010);
DISPLAY 0.489362 (-7215 3010);
PAINT MONO (-7215 3010);
FORCEPROP 0 LASTPIN (-7225 2950) $PN BU13
J 0
(-7215 2960);
DISPLAY 0.489362 (-7215 2960);
PAINT MONO (-7215 2960);
FORCEPROP 0 LASTPIN (-7225 2900) $PN BU15
J 0
(-7215 2910);
DISPLAY 0.489362 (-7215 2910);
PAINT MONO (-7215 2910);
FORCEPROP 0 LASTPIN (-7225 2850) $PN BU18
J 0
(-7215 2860);
DISPLAY 0.489362 (-7215 2860);
PAINT MONO (-7215 2860);
FORCEPROP 0 LASTPIN (-7225 2800) $PN BU20
J 0
(-7215 2810);
DISPLAY 0.489362 (-7215 2810);
PAINT MONO (-7215 2810);
FORCEPROP 0 LASTPIN (-7225 2750) $PN BU22
J 0
(-7215 2760);
DISPLAY 0.489362 (-7215 2760);
PAINT MONO (-7215 2760);
FORCEPROP 0 LASTPIN (-7225 2700) $PN BU25
J 0
(-7215 2710);
DISPLAY 0.489362 (-7215 2710);
PAINT MONO (-7215 2710);
FORCEPROP 0 LASTPIN (-7225 2650) $PN BU28
J 0
(-7215 2660);
DISPLAY 0.489362 (-7215 2660);
PAINT MONO (-7215 2660);
FORCEPROP 0 LASTPIN (-7225 2600) $PN BU31
J 0
(-7215 2610);
DISPLAY 0.489362 (-7215 2610);
PAINT MONO (-7215 2610);
FORCEPROP 0 LASTPIN (-7225 2550) $PN BU34
J 0
(-7215 2560);
DISPLAY 0.489362 (-7215 2560);
PAINT MONO (-7215 2560);
FORCEPROP 0 LASTPIN (-7225 2500) $PN BU35
J 0
(-7215 2510);
DISPLAY 0.489362 (-7215 2510);
PAINT MONO (-7215 2510);
FORCEPROP 0 LASTPIN (-7225 2450) $PN BU36
J 0
(-7215 2460);
DISPLAY 0.489362 (-7215 2460);
PAINT MONO (-7215 2460);
FORCEPROP 0 LASTPIN (-7225 2400) $PN BU40
J 0
(-7215 2410);
DISPLAY 0.489362 (-7215 2410);
PAINT MONO (-7215 2410);
FORCEPROP 0 LASTPIN (-7225 2350) $PN BU41
J 0
(-7215 2360);
DISPLAY 0.489362 (-7215 2360);
PAINT MONO (-7215 2360);
FORCEPROP 0 LASTPIN (-7225 2300) $PN BU42
J 0
(-7215 2310);
DISPLAY 0.489362 (-7215 2310);
PAINT MONO (-7215 2310);
FORCEPROP 0 LASTPIN (-7225 2250) $PN BU45
J 0
(-7215 2260);
DISPLAY 0.489362 (-7215 2260);
PAINT MONO (-7215 2260);
FORCEPROP 0 LASTPIN (-7225 2200) $PN BU48
J 0
(-7215 2210);
DISPLAY 0.489362 (-7215 2210);
PAINT MONO (-7215 2210);
FORCEPROP 0 LASTPIN (-7225 2150) $PN BU51
J 0
(-7215 2160);
DISPLAY 0.489362 (-7215 2160);
PAINT MONO (-7215 2160);
FORCEPROP 0 LASTPIN (-7225 2100) $PN BU54
J 0
(-7215 2110);
DISPLAY 0.489362 (-7215 2110);
PAINT MONO (-7215 2110);
FORCEPROP 0 LASTPIN (-7225 2050) $PN BU56
J 0
(-7215 2060);
DISPLAY 0.489362 (-7215 2060);
PAINT MONO (-7215 2060);
FORCEPROP 0 LASTPIN (-7225 2000) $PN BU58
J 0
(-7215 2010);
DISPLAY 0.489362 (-7215 2010);
PAINT MONO (-7215 2010);
FORCEPROP 0 LASTPIN (-7225 1950) $PN BU61
J 0
(-7215 1960);
DISPLAY 0.489362 (-7215 1960);
PAINT MONO (-7215 1960);
FORCEPROP 0 LASTPIN (-7225 1900) $PN BU63
J 0
(-7215 1910);
DISPLAY 0.489362 (-7215 1910);
PAINT MONO (-7215 1910);
FORCEPROP 0 LASTPIN (-7225 1850) $PN BU65
J 0
(-7215 1860);
DISPLAY 0.489362 (-7215 1860);
PAINT MONO (-7215 1860);
FORCEPROP 0 LASTPIN (-7225 1800) $PN BU68
J 0
(-7215 1810);
DISPLAY 0.489362 (-7215 1810);
PAINT MONO (-7215 1810);
FORCEPROP 0 LASTPIN (-7225 1750) $PN BU70
J 0
(-7215 1760);
DISPLAY 0.489362 (-7215 1760);
PAINT MONO (-7215 1760);
FORCEPROP 0 LASTPIN (-7225 1700) $PN BU72
J 0
(-7215 1710);
DISPLAY 0.489362 (-7215 1710);
PAINT MONO (-7215 1710);
FORCEPROP 0 LASTPIN (-7225 1650) $PN BU75
J 0
(-7215 1660);
DISPLAY 0.489362 (-7215 1660);
PAINT MONO (-7215 1660);
FORCEPROP 0 LASTPIN (-7225 1600) $PN BV3
J 0
(-7215 1610);
DISPLAY 0.489362 (-7215 1610);
PAINT MONO (-7215 1610);
FORCEPROP 0 LASTPIN (-7225 1550) $PN BV8
J 0
(-7215 1560);
DISPLAY 0.489362 (-7215 1560);
PAINT MONO (-7215 1560);
FORCEPROP 0 LASTPIN (-7225 1500) $PN BV10
J 0
(-7215 1510);
DISPLAY 0.489362 (-7215 1510);
PAINT MONO (-7215 1510);
FORCEPROP 0 LASTPIN (-7225 1450) $PN BV15
J 0
(-7215 1460);
DISPLAY 0.489362 (-7215 1460);
PAINT MONO (-7215 1460);
FORCEPROP 0 LASTPIN (-7225 1400) $PN BV17
J 0
(-7215 1410);
DISPLAY 0.489362 (-7215 1410);
PAINT MONO (-7215 1410);
FORCEPROP 0 LASTPIN (-7225 1350) $PN BV23
J 0
(-7215 1360);
DISPLAY 0.489362 (-7215 1360);
PAINT MONO (-7215 1360);
FORCEPROP 0 LASTPIN (-7225 1300) $PN BV24
J 0
(-7215 1310);
DISPLAY 0.489362 (-7215 1310);
PAINT MONO (-7215 1310);
FORCEPROP 0 LASTPIN (-7225 1250) $PN BV25
J 0
(-7215 1260);
DISPLAY 0.489362 (-7215 1260);
PAINT MONO (-7215 1260);
FORCEPROP 0 LASTPIN (-7225 1200) $PN BV26
J 0
(-7215 1210);
DISPLAY 0.489362 (-7215 1210);
PAINT MONO (-7215 1210);
FORCEPROP 0 LASTPIN (-7225 1150) $PN BV27
J 0
(-7215 1160);
DISPLAY 0.489362 (-7215 1160);
PAINT MONO (-7215 1160);
FORCEPROP 0 LASTPIN (-7225 1100) $PN BV28
J 0
(-7215 1110);
DISPLAY 0.489362 (-7215 1110);
PAINT MONO (-7215 1110);
FORCEPROP 0 LASTPIN (-7225 1050) $PN BV29
J 0
(-7215 1060);
DISPLAY 0.489362 (-7215 1060);
PAINT MONO (-7215 1060);
FORCEPROP 0 LASTPIN (-7225 1000) $PN BV30
J 0
(-7215 1010);
DISPLAY 0.489362 (-7215 1010);
PAINT MONO (-7215 1010);
FORCEPROP 0 LASTPIN (-7225 950) $PN BV31
J 0
(-7215 960);
DISPLAY 0.489362 (-7215 960);
PAINT MONO (-7215 960);
FORCEPROP 0 LASTPIN (-7225 900) $PN BV32
J 0
(-7215 910);
DISPLAY 0.489362 (-7215 910);
PAINT MONO (-7215 910);
FORCEPROP 0 LASTPIN (-7225 850) $PN BV33
J 0
(-7215 860);
DISPLAY 0.489362 (-7215 860);
PAINT MONO (-7215 860);
FORCEPROP 0 LASTPIN (-7225 800) $PN BV34
J 0
(-7215 810);
DISPLAY 0.489362 (-7215 810);
PAINT MONO (-7215 810);
FORCEPROP 0 LASTPIN (-7225 750) $PN BV37
J 0
(-7215 760);
DISPLAY 0.489362 (-7215 760);
PAINT MONO (-7215 760);
FORCEPROP 0 LASTPIN (-7225 700) $PN BV39
J 0
(-7215 710);
DISPLAY 0.489362 (-7215 710);
PAINT MONO (-7215 710);
FORCEPROP 0 LASTPIN (-7225 650) $PN BV43
J 0
(-7215 660);
DISPLAY 0.489362 (-7215 660);
PAINT MONO (-7215 660);
FORCEPROP 0 LASTPIN (-7225 600) $PN BV44
J 0
(-7215 610);
DISPLAY 0.489362 (-7215 610);
PAINT MONO (-7215 610);
FORCEPROP 0 LASTPIN (-7225 550) $PN BV45
J 0
(-7215 560);
DISPLAY 0.489362 (-7215 560);
PAINT MONO (-7215 560);
FORCEPROP 2 LAST PART_TYPE SMLF
J 0
(-8175 6700);
DISPLAY 1.021277 (-8175 6700);
FORCEPROP 1 LAST MATERIAL IO
J 0
(-8170 6532);
DISPLAY 0.489362 (-8170 6532);
PAINT SKYBLUE (-8170 6532);
FORCEPROP 2 LAST VALUE SOCKET6096_13568-001
J 0
(-8175 6575);
DISPLAY 0.489362 (-8175 6575);
PAINT SKYBLUE (-8175 6575);
FORCEPROP 1 LAST PART_NUMBER DGA^6000030
J 0
(-8175 6650);
DISPLAY 0.489362 (-8175 6650);
PAINT SKYBLUE (-8175 6650);
FORCEPROP 1 LAST NEEDS_NO_SIZE TRUE
J 0
(-7775 3450);
DISPLAY 0.723404 (-7775 3450);
PAINT GREEN (-7775 3450);
DISPLAY INVISIBLE (-7775 3450);
FORCEPROP 1 LAST CDS_LMAN_SYM_OUTLINE -400,3050,400,-3050
J 0
(-7775 3450);
DISPLAY 0.468085 (-7775 3450);
PAINT GREEN (-7775 3450);
DISPLAY INVISIBLE (-7775 3450);
FORCEPROP 2 LAST CDS_LIB pure_quanta
J 0
(-7775 3450);
DISPLAY INVISIBLE (-7775 3450);
FORCEPROP 1 LAST PATH I13
J 0
(-7775 3450);
DISPLAY 0.723404 (-7775 3450);
PAINT GREEN (-7775 3450);
DISPLAY INVISIBLE (-7775 3450);
FORCEADD GENOA_SP5..37
(-5750 3450);
FORCEPROP 1 LAST LOCATION U25
J 0
(-6145 6600);
DISPLAY 0.489362 (-6145 6600);
PAINT SKYBLUE (-6145 6600);
FORCEPROP 0 LAST $SEC 37
J 0
(-6125 6850);
DISPLAY 0.680851 (-6125 6850);
PAINT MONO (-6125 6850);
DISPLAY INVISIBLE (-6125 6850);
FORCEPROP 0 LAST CDS_SEC 37
J 0
(-6325 6725);
DISPLAY 1.021277 (-6325 6725);
DISPLAY INVISIBLE (-6325 6725);
FORCEPROP 0 LASTPIN (-6300 6350) $PN BV46
J 2
(-6310 6360);
DISPLAY 0.489362 (-6310 6360);
PAINT MONO (-6310 6360);
FORCEPROP 0 LASTPIN (-6300 6300) $PN BV47
J 2
(-6310 6310);
DISPLAY 0.489362 (-6310 6310);
PAINT MONO (-6310 6310);
FORCEPROP 0 LASTPIN (-6300 6250) $PN BV48
J 2
(-6310 6260);
DISPLAY 0.489362 (-6310 6260);
PAINT MONO (-6310 6260);
FORCEPROP 0 LASTPIN (-6300 6200) $PN BV49
J 2
(-6310 6210);
DISPLAY 0.489362 (-6310 6210);
PAINT MONO (-6310 6210);
FORCEPROP 0 LASTPIN (-6300 6150) $PN BV50
J 2
(-6310 6160);
DISPLAY 0.489362 (-6310 6160);
PAINT MONO (-6310 6160);
FORCEPROP 0 LASTPIN (-6300 6100) $PN BV51
J 2
(-6310 6110);
DISPLAY 0.489362 (-6310 6110);
PAINT MONO (-6310 6110);
FORCEPROP 0 LASTPIN (-6300 6050) $PN BV52
J 2
(-6310 6060);
DISPLAY 0.489362 (-6310 6060);
PAINT MONO (-6310 6060);
FORCEPROP 0 LASTPIN (-6300 6000) $PN BV53
J 2
(-6310 6010);
DISPLAY 0.489362 (-6310 6010);
PAINT MONO (-6310 6010);
FORCEPROP 0 LASTPIN (-6300 5950) $PN BV59
J 2
(-6310 5960);
DISPLAY 0.489362 (-6310 5960);
PAINT MONO (-6310 5960);
FORCEPROP 0 LASTPIN (-6300 5900) $PN BV61
J 2
(-6310 5910);
DISPLAY 0.489362 (-6310 5910);
PAINT MONO (-6310 5910);
FORCEPROP 0 LASTPIN (-6300 5850) $PN BV66
J 2
(-6310 5860);
DISPLAY 0.489362 (-6310 5860);
PAINT MONO (-6310 5860);
FORCEPROP 0 LASTPIN (-6300 5800) $PN BV68
J 2
(-6310 5810);
DISPLAY 0.489362 (-6310 5810);
PAINT MONO (-6310 5810);
FORCEPROP 0 LASTPIN (-6300 5750) $PN BV73
J 2
(-6310 5760);
DISPLAY 0.489362 (-6310 5760);
PAINT MONO (-6310 5760);
FORCEPROP 0 LASTPIN (-6300 5700) $PN BW1
J 2
(-6310 5710);
DISPLAY 0.489362 (-6310 5710);
PAINT MONO (-6310 5710);
FORCEPROP 0 LASTPIN (-6300 5650) $PN BW4
J 2
(-6310 5660);
DISPLAY 0.489362 (-6310 5660);
PAINT MONO (-6310 5660);
FORCEPROP 0 LASTPIN (-6300 5600) $PN BW6
J 2
(-6310 5610);
DISPLAY 0.489362 (-6310 5610);
PAINT MONO (-6310 5610);
FORCEPROP 0 LASTPIN (-6300 5550) $PN BW8
J 2
(-6310 5560);
DISPLAY 0.489362 (-6310 5560);
PAINT MONO (-6310 5560);
FORCEPROP 0 LASTPIN (-6300 5500) $PN BW11
J 2
(-6310 5510);
DISPLAY 0.489362 (-6310 5510);
PAINT MONO (-6310 5510);
FORCEPROP 0 LASTPIN (-6300 5450) $PN BW13
J 2
(-6310 5460);
DISPLAY 0.489362 (-6310 5460);
PAINT MONO (-6310 5460);
FORCEPROP 0 LASTPIN (-6300 5400) $PN BW15
J 2
(-6310 5410);
DISPLAY 0.489362 (-6310 5410);
PAINT MONO (-6310 5410);
FORCEPROP 0 LASTPIN (-6300 5350) $PN BW18
J 2
(-6310 5360);
DISPLAY 0.489362 (-6310 5360);
PAINT MONO (-6310 5360);
FORCEPROP 0 LASTPIN (-6300 5300) $PN BW20
J 2
(-6310 5310);
DISPLAY 0.489362 (-6310 5310);
PAINT MONO (-6310 5310);
FORCEPROP 0 LASTPIN (-6300 5250) $PN BW22
J 2
(-6310 5260);
DISPLAY 0.489362 (-6310 5260);
PAINT MONO (-6310 5260);
FORCEPROP 0 LASTPIN (-6300 5200) $PN BW28
J 2
(-6310 5210);
DISPLAY 0.489362 (-6310 5210);
PAINT MONO (-6310 5210);
FORCEPROP 0 LASTPIN (-6300 5150) $PN BW31
J 2
(-6310 5160);
DISPLAY 0.489362 (-6310 5160);
PAINT MONO (-6310 5160);
FORCEPROP 0 LASTPIN (-6300 5100) $PN BW34
J 2
(-6310 5110);
DISPLAY 0.489362 (-6310 5110);
PAINT MONO (-6310 5110);
FORCEPROP 0 LASTPIN (-6300 5050) $PN BW42
J 2
(-6310 5060);
DISPLAY 0.489362 (-6310 5060);
PAINT MONO (-6310 5060);
FORCEPROP 0 LASTPIN (-6300 5000) $PN BW45
J 2
(-6310 5010);
DISPLAY 0.489362 (-6310 5010);
PAINT MONO (-6310 5010);
FORCEPROP 0 LASTPIN (-6300 4950) $PN BW48
J 2
(-6310 4960);
DISPLAY 0.489362 (-6310 4960);
PAINT MONO (-6310 4960);
FORCEPROP 0 LASTPIN (-6300 4900) $PN BW51
J 2
(-6310 4910);
DISPLAY 0.489362 (-6310 4910);
PAINT MONO (-6310 4910);
FORCEPROP 0 LASTPIN (-6300 4850) $PN BW54
J 2
(-6310 4860);
DISPLAY 0.489362 (-6310 4860);
PAINT MONO (-6310 4860);
FORCEPROP 0 LASTPIN (-6300 4800) $PN BW56
J 2
(-6310 4810);
DISPLAY 0.489362 (-6310 4810);
PAINT MONO (-6310 4810);
FORCEPROP 0 LASTPIN (-6300 4750) $PN BW58
J 2
(-6310 4760);
DISPLAY 0.489362 (-6310 4760);
PAINT MONO (-6310 4760);
FORCEPROP 0 LASTPIN (-6300 4700) $PN BW61
J 2
(-6310 4710);
DISPLAY 0.489362 (-6310 4710);
PAINT MONO (-6310 4710);
FORCEPROP 0 LASTPIN (-6300 4650) $PN BW63
J 2
(-6310 4660);
DISPLAY 0.489362 (-6310 4660);
PAINT MONO (-6310 4660);
FORCEPROP 0 LASTPIN (-6300 4600) $PN BW65
J 2
(-6310 4610);
DISPLAY 0.489362 (-6310 4610);
PAINT MONO (-6310 4610);
FORCEPROP 0 LASTPIN (-6300 4550) $PN BW68
J 2
(-6310 4560);
DISPLAY 0.489362 (-6310 4560);
PAINT MONO (-6310 4560);
FORCEPROP 0 LASTPIN (-6300 4500) $PN BW70
J 2
(-6310 4510);
DISPLAY 0.489362 (-6310 4510);
PAINT MONO (-6310 4510);
FORCEPROP 0 LASTPIN (-6300 4450) $PN BW72
J 2
(-6310 4460);
DISPLAY 0.489362 (-6310 4460);
PAINT MONO (-6310 4460);
FORCEPROP 0 LASTPIN (-6300 4400) $PN BW75
J 2
(-6310 4410);
DISPLAY 0.489362 (-6310 4410);
PAINT MONO (-6310 4410);
FORCEPROP 0 LASTPIN (-6300 4350) $PN BY3
J 2
(-6310 4360);
DISPLAY 0.489362 (-6310 4360);
PAINT MONO (-6310 4360);
FORCEPROP 0 LASTPIN (-6300 4300) $PN BY5
J 2
(-6310 4310);
DISPLAY 0.489362 (-6310 4310);
PAINT MONO (-6310 4310);
FORCEPROP 0 LASTPIN (-6300 4250) $PN BY8
J 2
(-6310 4260);
DISPLAY 0.489362 (-6310 4260);
PAINT MONO (-6310 4260);
FORCEPROP 0 LASTPIN (-6300 4200) $PN BY10
J 2
(-6310 4210);
DISPLAY 0.489362 (-6310 4210);
PAINT MONO (-6310 4210);
FORCEPROP 0 LASTPIN (-6300 4150) $PN BY12
J 2
(-6310 4160);
DISPLAY 0.489362 (-6310 4160);
PAINT MONO (-6310 4160);
FORCEPROP 0 LASTPIN (-6300 4100) $PN BY15
J 2
(-6310 4110);
DISPLAY 0.489362 (-6310 4110);
PAINT MONO (-6310 4110);
FORCEPROP 0 LASTPIN (-6300 4050) $PN BY17
J 2
(-6310 4060);
DISPLAY 0.489362 (-6310 4060);
PAINT MONO (-6310 4060);
FORCEPROP 0 LASTPIN (-6300 4000) $PN BY19
J 2
(-6310 4010);
DISPLAY 0.489362 (-6310 4010);
PAINT MONO (-6310 4010);
FORCEPROP 0 LASTPIN (-6300 3950) $PN BY22
J 2
(-6310 3960);
DISPLAY 0.489362 (-6310 3960);
PAINT MONO (-6310 3960);
FORCEPROP 0 LASTPIN (-6300 3900) $PN BY25
J 2
(-6310 3910);
DISPLAY 0.489362 (-6310 3910);
PAINT MONO (-6310 3910);
FORCEPROP 0 LASTPIN (-6300 3850) $PN BY28
J 2
(-6310 3860);
DISPLAY 0.489362 (-6310 3860);
PAINT MONO (-6310 3860);
FORCEPROP 0 LASTPIN (-6300 3800) $PN BY31
J 2
(-6310 3810);
DISPLAY 0.489362 (-6310 3810);
PAINT MONO (-6310 3810);
FORCEPROP 0 LASTPIN (-6300 3750) $PN BY34
J 2
(-6310 3760);
DISPLAY 0.489362 (-6310 3760);
PAINT MONO (-6310 3760);
FORCEPROP 0 LASTPIN (-6300 3700) $PN BY37
J 2
(-6310 3710);
DISPLAY 0.489362 (-6310 3710);
PAINT MONO (-6310 3710);
FORCEPROP 0 LASTPIN (-6300 3650) $PN BY39
J 2
(-6310 3660);
DISPLAY 0.489362 (-6310 3660);
PAINT MONO (-6310 3660);
FORCEPROP 0 LASTPIN (-6300 3600) $PN BY42
J 2
(-6310 3610);
DISPLAY 0.489362 (-6310 3610);
PAINT MONO (-6310 3610);
FORCEPROP 0 LASTPIN (-6300 3550) $PN BY45
J 2
(-6310 3560);
DISPLAY 0.489362 (-6310 3560);
PAINT MONO (-6310 3560);
FORCEPROP 0 LASTPIN (-6300 3500) $PN BY48
J 2
(-6310 3510);
DISPLAY 0.489362 (-6310 3510);
PAINT MONO (-6310 3510);
FORCEPROP 0 LASTPIN (-6300 3450) $PN BY51
J 2
(-6310 3460);
DISPLAY 0.489362 (-6310 3460);
PAINT MONO (-6310 3460);
FORCEPROP 0 LASTPIN (-6300 3400) $PN BY54
J 2
(-6310 3410);
DISPLAY 0.489362 (-6310 3410);
PAINT MONO (-6310 3410);
FORCEPROP 0 LASTPIN (-6300 3350) $PN BY57
J 2
(-6310 3360);
DISPLAY 0.489362 (-6310 3360);
PAINT MONO (-6310 3360);
FORCEPROP 0 LASTPIN (-6300 3300) $PN BY59
J 2
(-6310 3310);
DISPLAY 0.489362 (-6310 3310);
PAINT MONO (-6310 3310);
FORCEPROP 0 LASTPIN (-6300 3250) $PN BY61
J 2
(-6310 3260);
DISPLAY 0.489362 (-6310 3260);
PAINT MONO (-6310 3260);
FORCEPROP 0 LASTPIN (-6300 3200) $PN BY64
J 2
(-6310 3210);
DISPLAY 0.489362 (-6310 3210);
PAINT MONO (-6310 3210);
FORCEPROP 0 LASTPIN (-6300 3150) $PN BY66
J 2
(-6310 3160);
DISPLAY 0.489362 (-6310 3160);
PAINT MONO (-6310 3160);
FORCEPROP 0 LASTPIN (-6300 3100) $PN BY68
J 2
(-6310 3110);
DISPLAY 0.489362 (-6310 3110);
PAINT MONO (-6310 3110);
FORCEPROP 0 LASTPIN (-6300 3050) $PN BY71
J 2
(-6310 3060);
DISPLAY 0.489362 (-6310 3060);
PAINT MONO (-6310 3060);
FORCEPROP 0 LASTPIN (-6300 3000) $PN BY73
J 2
(-6310 3010);
DISPLAY 0.489362 (-6310 3010);
PAINT MONO (-6310 3010);
FORCEPROP 0 LASTPIN (-6300 2950) $PN CA1
J 2
(-6310 2960);
DISPLAY 0.489362 (-6310 2960);
PAINT MONO (-6310 2960);
FORCEPROP 0 LASTPIN (-6300 2900) $PN CA6
J 2
(-6310 2910);
DISPLAY 0.489362 (-6310 2910);
PAINT MONO (-6310 2910);
FORCEPROP 0 LASTPIN (-6300 2850) $PN CA8
J 2
(-6310 2860);
DISPLAY 0.489362 (-6310 2860);
PAINT MONO (-6310 2860);
FORCEPROP 0 LASTPIN (-6300 2800) $PN CA13
J 2
(-6310 2810);
DISPLAY 0.489362 (-6310 2810);
PAINT MONO (-6310 2810);
FORCEPROP 0 LASTPIN (-6300 2750) $PN CA15
J 2
(-6310 2760);
DISPLAY 0.489362 (-6310 2760);
PAINT MONO (-6310 2760);
FORCEPROP 0 LASTPIN (-6300 2700) $PN CA20
J 2
(-6310 2710);
DISPLAY 0.489362 (-6310 2710);
PAINT MONO (-6310 2710);
FORCEPROP 0 LASTPIN (-6300 2650) $PN CA22
J 2
(-6310 2660);
DISPLAY 0.489362 (-6310 2660);
PAINT MONO (-6310 2660);
FORCEPROP 0 LASTPIN (-6300 2600) $PN CA25
J 2
(-6310 2610);
DISPLAY 0.489362 (-6310 2610);
PAINT MONO (-6310 2610);
FORCEPROP 0 LASTPIN (-6300 2550) $PN CA28
J 2
(-6310 2560);
DISPLAY 0.489362 (-6310 2560);
PAINT MONO (-6310 2560);
FORCEPROP 0 LASTPIN (-6300 2500) $PN CA31
J 2
(-6310 2510);
DISPLAY 0.489362 (-6310 2510);
PAINT MONO (-6310 2510);
FORCEPROP 0 LASTPIN (-6300 2450) $PN CA34
J 2
(-6310 2460);
DISPLAY 0.489362 (-6310 2460);
PAINT MONO (-6310 2460);
FORCEPROP 0 LASTPIN (-6300 2400) $PN CA35
J 2
(-6310 2410);
DISPLAY 0.489362 (-6310 2410);
PAINT MONO (-6310 2410);
FORCEPROP 0 LASTPIN (-6300 2350) $PN CA36
J 2
(-6310 2360);
DISPLAY 0.489362 (-6310 2360);
PAINT MONO (-6310 2360);
FORCEPROP 0 LASTPIN (-6300 2300) $PN CA40
J 2
(-6310 2310);
DISPLAY 0.489362 (-6310 2310);
PAINT MONO (-6310 2310);
FORCEPROP 0 LASTPIN (-6300 2250) $PN CA41
J 2
(-6310 2260);
DISPLAY 0.489362 (-6310 2260);
PAINT MONO (-6310 2260);
FORCEPROP 0 LASTPIN (-6300 2200) $PN CA42
J 2
(-6310 2210);
DISPLAY 0.489362 (-6310 2210);
PAINT MONO (-6310 2210);
FORCEPROP 0 LASTPIN (-6300 2150) $PN CA45
J 2
(-6310 2160);
DISPLAY 0.489362 (-6310 2160);
PAINT MONO (-6310 2160);
FORCEPROP 0 LASTPIN (-6300 2100) $PN CA48
J 2
(-6310 2110);
DISPLAY 0.489362 (-6310 2110);
PAINT MONO (-6310 2110);
FORCEPROP 0 LASTPIN (-6300 2050) $PN CA51
J 2
(-6310 2060);
DISPLAY 0.489362 (-6310 2060);
PAINT MONO (-6310 2060);
FORCEPROP 0 LASTPIN (-6300 2000) $PN CA54
J 2
(-6310 2010);
DISPLAY 0.489362 (-6310 2010);
PAINT MONO (-6310 2010);
FORCEPROP 0 LASTPIN (-6300 1950) $PN CA56
J 2
(-6310 1960);
DISPLAY 0.489362 (-6310 1960);
PAINT MONO (-6310 1960);
FORCEPROP 0 LASTPIN (-6300 1900) $PN CA61
J 2
(-6310 1910);
DISPLAY 0.489362 (-6310 1910);
PAINT MONO (-6310 1910);
FORCEPROP 0 LASTPIN (-6300 1850) $PN CA63
J 2
(-6310 1860);
DISPLAY 0.489362 (-6310 1860);
PAINT MONO (-6310 1860);
FORCEPROP 0 LASTPIN (-6300 1800) $PN CA68
J 2
(-6310 1810);
DISPLAY 0.489362 (-6310 1810);
PAINT MONO (-6310 1810);
FORCEPROP 0 LASTPIN (-6300 1750) $PN CA70
J 2
(-6310 1760);
DISPLAY 0.489362 (-6310 1760);
PAINT MONO (-6310 1760);
FORCEPROP 0 LASTPIN (-6300 1700) $PN CA75
J 2
(-6310 1710);
DISPLAY 0.489362 (-6310 1710);
PAINT MONO (-6310 1710);
FORCEPROP 0 LASTPIN (-6300 1650) $PN CB3
J 2
(-6310 1660);
DISPLAY 0.489362 (-6310 1660);
PAINT MONO (-6310 1660);
FORCEPROP 0 LASTPIN (-6300 1600) $PN CB5
J 2
(-6310 1610);
DISPLAY 0.489362 (-6310 1610);
PAINT MONO (-6310 1610);
FORCEPROP 0 LASTPIN (-6300 1550) $PN CB8
J 2
(-6310 1560);
DISPLAY 0.489362 (-6310 1560);
PAINT MONO (-6310 1560);
FORCEPROP 0 LASTPIN (-6300 1500) $PN CB10
J 2
(-6310 1510);
DISPLAY 0.489362 (-6310 1510);
PAINT MONO (-6310 1510);
FORCEPROP 0 LASTPIN (-6300 1450) $PN CB12
J 2
(-6310 1460);
DISPLAY 0.489362 (-6310 1460);
PAINT MONO (-6310 1460);
FORCEPROP 0 LASTPIN (-6300 1400) $PN CB15
J 2
(-6310 1410);
DISPLAY 0.489362 (-6310 1410);
PAINT MONO (-6310 1410);
FORCEPROP 0 LASTPIN (-6300 1350) $PN CB17
J 2
(-6310 1360);
DISPLAY 0.489362 (-6310 1360);
PAINT MONO (-6310 1360);
FORCEPROP 0 LASTPIN (-6300 1300) $PN CB19
J 2
(-6310 1310);
DISPLAY 0.489362 (-6310 1310);
PAINT MONO (-6310 1310);
FORCEPROP 0 LASTPIN (-6300 1250) $PN CB23
J 2
(-6310 1260);
DISPLAY 0.489362 (-6310 1260);
PAINT MONO (-6310 1260);
FORCEPROP 0 LASTPIN (-6300 1200) $PN CB24
J 2
(-6310 1210);
DISPLAY 0.489362 (-6310 1210);
PAINT MONO (-6310 1210);
FORCEPROP 0 LASTPIN (-6300 1150) $PN CB25
J 2
(-6310 1160);
DISPLAY 0.489362 (-6310 1160);
PAINT MONO (-6310 1160);
FORCEPROP 0 LASTPIN (-6300 1100) $PN CB26
J 2
(-6310 1110);
DISPLAY 0.489362 (-6310 1110);
PAINT MONO (-6310 1110);
FORCEPROP 0 LASTPIN (-6300 1050) $PN CB27
J 2
(-6310 1060);
DISPLAY 0.489362 (-6310 1060);
PAINT MONO (-6310 1060);
FORCEPROP 0 LASTPIN (-6300 1000) $PN CB28
J 2
(-6310 1010);
DISPLAY 0.489362 (-6310 1010);
PAINT MONO (-6310 1010);
FORCEPROP 0 LASTPIN (-6300 950) $PN CB29
J 2
(-6310 960);
DISPLAY 0.489362 (-6310 960);
PAINT MONO (-6310 960);
FORCEPROP 0 LASTPIN (-6300 900) $PN CB30
J 2
(-6310 910);
DISPLAY 0.489362 (-6310 910);
PAINT MONO (-6310 910);
FORCEPROP 0 LASTPIN (-6300 850) $PN CB31
J 2
(-6310 860);
DISPLAY 0.489362 (-6310 860);
PAINT MONO (-6310 860);
FORCEPROP 0 LASTPIN (-6300 800) $PN CB32
J 2
(-6310 810);
DISPLAY 0.489362 (-6310 810);
PAINT MONO (-6310 810);
FORCEPROP 0 LASTPIN (-6300 750) $PN CB33
J 2
(-6310 760);
DISPLAY 0.489362 (-6310 760);
PAINT MONO (-6310 760);
FORCEPROP 0 LASTPIN (-6300 700) $PN CB34
J 2
(-6310 710);
DISPLAY 0.489362 (-6310 710);
PAINT MONO (-6310 710);
FORCEPROP 0 LASTPIN (-6300 650) $PN CB37
J 2
(-6310 660);
DISPLAY 0.489362 (-6310 660);
PAINT MONO (-6310 660);
FORCEPROP 0 LASTPIN (-6300 600) $PN CB39
J 2
(-6310 610);
DISPLAY 0.489362 (-6310 610);
PAINT MONO (-6310 610);
FORCEPROP 0 LASTPIN (-6300 550) $PN CB42
J 2
(-6310 560);
DISPLAY 0.489362 (-6310 560);
PAINT MONO (-6310 560);
FORCEPROP 0 LASTPIN (-6300 500) $PN CB43
J 2
(-6310 510);
DISPLAY 0.489362 (-6310 510);
PAINT MONO (-6310 510);
FORCEPROP 0 LASTPIN (-5200 6300) $PN CB45
J 0
(-5190 6310);
DISPLAY 0.489362 (-5190 6310);
PAINT MONO (-5190 6310);
FORCEPROP 0 LASTPIN (-5200 6250) $PN CB46
J 0
(-5190 6260);
DISPLAY 0.489362 (-5190 6260);
PAINT MONO (-5190 6260);
FORCEPROP 0 LASTPIN (-5200 6200) $PN CB47
J 0
(-5190 6210);
DISPLAY 0.489362 (-5190 6210);
PAINT MONO (-5190 6210);
FORCEPROP 0 LASTPIN (-5200 6150) $PN CB48
J 0
(-5190 6160);
DISPLAY 0.489362 (-5190 6160);
PAINT MONO (-5190 6160);
FORCEPROP 0 LASTPIN (-5200 6100) $PN CB49
J 0
(-5190 6110);
DISPLAY 0.489362 (-5190 6110);
PAINT MONO (-5190 6110);
FORCEPROP 0 LASTPIN (-5200 6050) $PN CB50
J 0
(-5190 6060);
DISPLAY 0.489362 (-5190 6060);
PAINT MONO (-5190 6060);
FORCEPROP 0 LASTPIN (-5200 6000) $PN CB51
J 0
(-5190 6010);
DISPLAY 0.489362 (-5190 6010);
PAINT MONO (-5190 6010);
FORCEPROP 0 LASTPIN (-5200 5950) $PN CB52
J 0
(-5190 5960);
DISPLAY 0.489362 (-5190 5960);
PAINT MONO (-5190 5960);
FORCEPROP 0 LASTPIN (-5200 5900) $PN CB53
J 0
(-5190 5910);
DISPLAY 0.489362 (-5190 5910);
PAINT MONO (-5190 5910);
FORCEPROP 0 LASTPIN (-5200 5850) $PN CB57
J 0
(-5190 5860);
DISPLAY 0.489362 (-5190 5860);
PAINT MONO (-5190 5860);
FORCEPROP 0 LASTPIN (-5200 5800) $PN CB59
J 0
(-5190 5810);
DISPLAY 0.489362 (-5190 5810);
PAINT MONO (-5190 5810);
FORCEPROP 0 LASTPIN (-5200 5750) $PN CB61
J 0
(-5190 5760);
DISPLAY 0.489362 (-5190 5760);
PAINT MONO (-5190 5760);
FORCEPROP 0 LASTPIN (-5200 5700) $PN CB64
J 0
(-5190 5710);
DISPLAY 0.489362 (-5190 5710);
PAINT MONO (-5190 5710);
FORCEPROP 0 LASTPIN (-5200 5650) $PN CB66
J 0
(-5190 5660);
DISPLAY 0.489362 (-5190 5660);
PAINT MONO (-5190 5660);
FORCEPROP 0 LASTPIN (-5200 5600) $PN CB68
J 0
(-5190 5610);
DISPLAY 0.489362 (-5190 5610);
PAINT MONO (-5190 5610);
FORCEPROP 0 LASTPIN (-5200 5550) $PN CB71
J 0
(-5190 5560);
DISPLAY 0.489362 (-5190 5560);
PAINT MONO (-5190 5560);
FORCEPROP 0 LASTPIN (-5200 5500) $PN CB73
J 0
(-5190 5510);
DISPLAY 0.489362 (-5190 5510);
PAINT MONO (-5190 5510);
FORCEPROP 0 LASTPIN (-5200 5450) $PN CC1
J 0
(-5190 5460);
DISPLAY 0.489362 (-5190 5460);
PAINT MONO (-5190 5460);
FORCEPROP 0 LASTPIN (-5200 5400) $PN CC4
J 0
(-5190 5410);
DISPLAY 0.489362 (-5190 5410);
PAINT MONO (-5190 5410);
FORCEPROP 0 LASTPIN (-5200 5350) $PN CC6
J 0
(-5190 5360);
DISPLAY 0.489362 (-5190 5360);
PAINT MONO (-5190 5360);
FORCEPROP 0 LASTPIN (-5200 5300) $PN CC8
J 0
(-5190 5310);
DISPLAY 0.489362 (-5190 5310);
PAINT MONO (-5190 5310);
FORCEPROP 0 LASTPIN (-5200 5250) $PN CC11
J 0
(-5190 5260);
DISPLAY 0.489362 (-5190 5260);
PAINT MONO (-5190 5260);
FORCEPROP 0 LASTPIN (-5200 5200) $PN CC13
J 0
(-5190 5210);
DISPLAY 0.489362 (-5190 5210);
PAINT MONO (-5190 5210);
FORCEPROP 0 LASTPIN (-5200 5150) $PN CC15
J 0
(-5190 5160);
DISPLAY 0.489362 (-5190 5160);
PAINT MONO (-5190 5160);
FORCEPROP 0 LASTPIN (-5200 5100) $PN CC18
J 0
(-5190 5110);
DISPLAY 0.489362 (-5190 5110);
PAINT MONO (-5190 5110);
FORCEPROP 0 LASTPIN (-5200 5050) $PN CC20
J 0
(-5190 5060);
DISPLAY 0.489362 (-5190 5060);
PAINT MONO (-5190 5060);
FORCEPROP 0 LASTPIN (-5200 5000) $PN CC25
J 0
(-5190 5010);
DISPLAY 0.489362 (-5190 5010);
PAINT MONO (-5190 5010);
FORCEPROP 0 LASTPIN (-5200 4950) $PN CC28
J 0
(-5190 4960);
DISPLAY 0.489362 (-5190 4960);
PAINT MONO (-5190 4960);
FORCEPROP 0 LASTPIN (-5200 4900) $PN CC31
J 0
(-5190 4910);
DISPLAY 0.489362 (-5190 4910);
PAINT MONO (-5190 4910);
FORCEPROP 0 LASTPIN (-5200 4850) $PN CC34
J 0
(-5190 4860);
DISPLAY 0.489362 (-5190 4860);
PAINT MONO (-5190 4860);
FORCEPROP 0 LASTPIN (-5200 4800) $PN CC42
J 0
(-5190 4810);
DISPLAY 0.489362 (-5190 4810);
PAINT MONO (-5190 4810);
FORCEPROP 0 LASTPIN (-5200 4750) $PN CC45
J 0
(-5190 4760);
DISPLAY 0.489362 (-5190 4760);
PAINT MONO (-5190 4760);
FORCEPROP 0 LASTPIN (-5200 4700) $PN CC48
J 0
(-5190 4710);
DISPLAY 0.489362 (-5190 4710);
PAINT MONO (-5190 4710);
FORCEPROP 0 LASTPIN (-5200 4650) $PN CC51
J 0
(-5190 4660);
DISPLAY 0.489362 (-5190 4660);
PAINT MONO (-5190 4660);
FORCEPROP 0 LASTPIN (-5200 4600) $PN CC54
J 0
(-5190 4610);
DISPLAY 0.489362 (-5190 4610);
PAINT MONO (-5190 4610);
FORCEPROP 0 LASTPIN (-5200 4550) $PN CC56
J 0
(-5190 4560);
DISPLAY 0.489362 (-5190 4560);
PAINT MONO (-5190 4560);
FORCEPROP 0 LASTPIN (-5200 4500) $PN CC58
J 0
(-5190 4510);
DISPLAY 0.489362 (-5190 4510);
PAINT MONO (-5190 4510);
FORCEPROP 0 LASTPIN (-5200 4450) $PN CC61
J 0
(-5190 4460);
DISPLAY 0.489362 (-5190 4460);
PAINT MONO (-5190 4460);
FORCEPROP 0 LASTPIN (-5200 4400) $PN CC63
J 0
(-5190 4410);
DISPLAY 0.489362 (-5190 4410);
PAINT MONO (-5190 4410);
FORCEPROP 0 LASTPIN (-5200 4350) $PN CC65
J 0
(-5190 4360);
DISPLAY 0.489362 (-5190 4360);
PAINT MONO (-5190 4360);
FORCEPROP 0 LASTPIN (-5200 4300) $PN CC68
J 0
(-5190 4310);
DISPLAY 0.489362 (-5190 4310);
PAINT MONO (-5190 4310);
FORCEPROP 0 LASTPIN (-5200 4250) $PN CC70
J 0
(-5190 4260);
DISPLAY 0.489362 (-5190 4260);
PAINT MONO (-5190 4260);
FORCEPROP 0 LASTPIN (-5200 4200) $PN CC72
J 0
(-5190 4210);
DISPLAY 0.489362 (-5190 4210);
PAINT MONO (-5190 4210);
FORCEPROP 0 LASTPIN (-5200 4150) $PN CC75
J 0
(-5190 4160);
DISPLAY 0.489362 (-5190 4160);
PAINT MONO (-5190 4160);
FORCEPROP 0 LASTPIN (-5200 4100) $PN CD3
J 0
(-5190 4110);
DISPLAY 0.489362 (-5190 4110);
PAINT MONO (-5190 4110);
FORCEPROP 0 LASTPIN (-5200 4050) $PN CD8
J 0
(-5190 4060);
DISPLAY 0.489362 (-5190 4060);
PAINT MONO (-5190 4060);
FORCEPROP 0 LASTPIN (-5200 4000) $PN CD10
J 0
(-5190 4010);
DISPLAY 0.489362 (-5190 4010);
PAINT MONO (-5190 4010);
FORCEPROP 0 LASTPIN (-5200 3950) $PN CD15
J 0
(-5190 3960);
DISPLAY 0.489362 (-5190 3960);
PAINT MONO (-5190 3960);
FORCEPROP 0 LASTPIN (-5200 3900) $PN CD17
J 0
(-5190 3910);
DISPLAY 0.489362 (-5190 3910);
PAINT MONO (-5190 3910);
FORCEPROP 0 LASTPIN (-5200 3850) $PN CD22
J 0
(-5190 3860);
DISPLAY 0.489362 (-5190 3860);
PAINT MONO (-5190 3860);
FORCEPROP 0 LASTPIN (-5200 3800) $PN CD25
J 0
(-5190 3810);
DISPLAY 0.489362 (-5190 3810);
PAINT MONO (-5190 3810);
FORCEPROP 0 LASTPIN (-5200 3750) $PN CD28
J 0
(-5190 3760);
DISPLAY 0.489362 (-5190 3760);
PAINT MONO (-5190 3760);
FORCEPROP 0 LASTPIN (-5200 3700) $PN CD31
J 0
(-5190 3710);
DISPLAY 0.489362 (-5190 3710);
PAINT MONO (-5190 3710);
FORCEPROP 0 LASTPIN (-5200 3650) $PN CD34
J 0
(-5190 3660);
DISPLAY 0.489362 (-5190 3660);
PAINT MONO (-5190 3660);
FORCEPROP 0 LASTPIN (-5200 3600) $PN CD37
J 0
(-5190 3610);
DISPLAY 0.489362 (-5190 3610);
PAINT MONO (-5190 3610);
FORCEPROP 0 LASTPIN (-5200 3550) $PN CD39
J 0
(-5190 3560);
DISPLAY 0.489362 (-5190 3560);
PAINT MONO (-5190 3560);
FORCEPROP 0 LASTPIN (-5200 3500) $PN CD42
J 0
(-5190 3510);
DISPLAY 0.489362 (-5190 3510);
PAINT MONO (-5190 3510);
FORCEPROP 0 LASTPIN (-5200 3450) $PN CD45
J 0
(-5190 3460);
DISPLAY 0.489362 (-5190 3460);
PAINT MONO (-5190 3460);
FORCEPROP 0 LASTPIN (-5200 3400) $PN CD48
J 0
(-5190 3410);
DISPLAY 0.489362 (-5190 3410);
PAINT MONO (-5190 3410);
FORCEPROP 0 LASTPIN (-5200 3350) $PN CD51
J 0
(-5190 3360);
DISPLAY 0.489362 (-5190 3360);
PAINT MONO (-5190 3360);
FORCEPROP 0 LASTPIN (-5200 3300) $PN CD54
J 0
(-5190 3310);
DISPLAY 0.489362 (-5190 3310);
PAINT MONO (-5190 3310);
FORCEPROP 0 LASTPIN (-5200 3250) $PN CD59
J 0
(-5190 3260);
DISPLAY 0.489362 (-5190 3260);
PAINT MONO (-5190 3260);
FORCEPROP 0 LASTPIN (-5200 3200) $PN CD61
J 0
(-5190 3210);
DISPLAY 0.489362 (-5190 3210);
PAINT MONO (-5190 3210);
FORCEPROP 0 LASTPIN (-5200 3150) $PN CD66
J 0
(-5190 3160);
DISPLAY 0.489362 (-5190 3160);
PAINT MONO (-5190 3160);
FORCEPROP 0 LASTPIN (-5200 3100) $PN CD68
J 0
(-5190 3110);
DISPLAY 0.489362 (-5190 3110);
PAINT MONO (-5190 3110);
FORCEPROP 0 LASTPIN (-5200 3050) $PN CD73
J 0
(-5190 3060);
DISPLAY 0.489362 (-5190 3060);
PAINT MONO (-5190 3060);
FORCEPROP 0 LASTPIN (-5200 3000) $PN CE1
J 0
(-5190 3010);
DISPLAY 0.489362 (-5190 3010);
PAINT MONO (-5190 3010);
FORCEPROP 0 LASTPIN (-5200 2950) $PN CE4
J 0
(-5190 2960);
DISPLAY 0.489362 (-5190 2960);
PAINT MONO (-5190 2960);
FORCEPROP 0 LASTPIN (-5200 2900) $PN CE6
J 0
(-5190 2910);
DISPLAY 0.489362 (-5190 2910);
PAINT MONO (-5190 2910);
FORCEPROP 0 LASTPIN (-5200 2850) $PN CE8
J 0
(-5190 2860);
DISPLAY 0.489362 (-5190 2860);
PAINT MONO (-5190 2860);
FORCEPROP 0 LASTPIN (-5200 2800) $PN CE11
J 0
(-5190 2810);
DISPLAY 0.489362 (-5190 2810);
PAINT MONO (-5190 2810);
FORCEPROP 0 LASTPIN (-5200 2750) $PN CE13
J 0
(-5190 2760);
DISPLAY 0.489362 (-5190 2760);
PAINT MONO (-5190 2760);
FORCEPROP 0 LASTPIN (-5200 2700) $PN CE15
J 0
(-5190 2710);
DISPLAY 0.489362 (-5190 2710);
PAINT MONO (-5190 2710);
FORCEPROP 0 LASTPIN (-5200 2650) $PN CE18
J 0
(-5190 2660);
DISPLAY 0.489362 (-5190 2660);
PAINT MONO (-5190 2660);
FORCEPROP 0 LASTPIN (-5200 2600) $PN CE20
J 0
(-5190 2610);
DISPLAY 0.489362 (-5190 2610);
PAINT MONO (-5190 2610);
FORCEPROP 0 LASTPIN (-5200 2550) $PN CE22
J 0
(-5190 2560);
DISPLAY 0.489362 (-5190 2560);
PAINT MONO (-5190 2560);
FORCEPROP 0 LASTPIN (-5200 2500) $PN CE25
J 0
(-5190 2510);
DISPLAY 0.489362 (-5190 2510);
PAINT MONO (-5190 2510);
FORCEPROP 0 LASTPIN (-5200 2450) $PN CE28
J 0
(-5190 2460);
DISPLAY 0.489362 (-5190 2460);
PAINT MONO (-5190 2460);
FORCEPROP 0 LASTPIN (-5200 2400) $PN CE31
J 0
(-5190 2410);
DISPLAY 0.489362 (-5190 2410);
PAINT MONO (-5190 2410);
FORCEPROP 0 LASTPIN (-5200 2350) $PN CE34
J 0
(-5190 2360);
DISPLAY 0.489362 (-5190 2360);
PAINT MONO (-5190 2360);
FORCEPROP 0 LASTPIN (-5200 2300) $PN CE35
J 0
(-5190 2310);
DISPLAY 0.489362 (-5190 2310);
PAINT MONO (-5190 2310);
FORCEPROP 0 LASTPIN (-5200 2250) $PN CE36
J 0
(-5190 2260);
DISPLAY 0.489362 (-5190 2260);
PAINT MONO (-5190 2260);
FORCEPROP 0 LASTPIN (-5200 2200) $PN CE40
J 0
(-5190 2210);
DISPLAY 0.489362 (-5190 2210);
PAINT MONO (-5190 2210);
FORCEPROP 0 LASTPIN (-5200 2150) $PN CE41
J 0
(-5190 2160);
DISPLAY 0.489362 (-5190 2160);
PAINT MONO (-5190 2160);
FORCEPROP 0 LASTPIN (-5200 2100) $PN CE42
J 0
(-5190 2110);
DISPLAY 0.489362 (-5190 2110);
PAINT MONO (-5190 2110);
FORCEPROP 0 LASTPIN (-5200 2050) $PN CE45
J 0
(-5190 2060);
DISPLAY 0.489362 (-5190 2060);
PAINT MONO (-5190 2060);
FORCEPROP 0 LASTPIN (-5200 2000) $PN CE48
J 0
(-5190 2010);
DISPLAY 0.489362 (-5190 2010);
PAINT MONO (-5190 2010);
FORCEPROP 0 LASTPIN (-5200 1950) $PN CE51
J 0
(-5190 1960);
DISPLAY 0.489362 (-5190 1960);
PAINT MONO (-5190 1960);
FORCEPROP 0 LASTPIN (-5200 1900) $PN CE54
J 0
(-5190 1910);
DISPLAY 0.489362 (-5190 1910);
PAINT MONO (-5190 1910);
FORCEPROP 0 LASTPIN (-5200 1850) $PN CE56
J 0
(-5190 1860);
DISPLAY 0.489362 (-5190 1860);
PAINT MONO (-5190 1860);
FORCEPROP 0 LASTPIN (-5200 1800) $PN CE58
J 0
(-5190 1810);
DISPLAY 0.489362 (-5190 1810);
PAINT MONO (-5190 1810);
FORCEPROP 0 LASTPIN (-5200 1750) $PN CE61
J 0
(-5190 1760);
DISPLAY 0.489362 (-5190 1760);
PAINT MONO (-5190 1760);
FORCEPROP 0 LASTPIN (-5200 1700) $PN CE63
J 0
(-5190 1710);
DISPLAY 0.489362 (-5190 1710);
PAINT MONO (-5190 1710);
FORCEPROP 0 LASTPIN (-5200 1650) $PN CE65
J 0
(-5190 1660);
DISPLAY 0.489362 (-5190 1660);
PAINT MONO (-5190 1660);
FORCEPROP 0 LASTPIN (-5200 1600) $PN CE68
J 0
(-5190 1610);
DISPLAY 0.489362 (-5190 1610);
PAINT MONO (-5190 1610);
FORCEPROP 0 LASTPIN (-5200 1550) $PN CE70
J 0
(-5190 1560);
DISPLAY 0.489362 (-5190 1560);
PAINT MONO (-5190 1560);
FORCEPROP 0 LASTPIN (-5200 1500) $PN CE72
J 0
(-5190 1510);
DISPLAY 0.489362 (-5190 1510);
PAINT MONO (-5190 1510);
FORCEPROP 0 LASTPIN (-5200 1450) $PN CE75
J 0
(-5190 1460);
DISPLAY 0.489362 (-5190 1460);
PAINT MONO (-5190 1460);
FORCEPROP 0 LASTPIN (-5200 1400) $PN CF3
J 0
(-5190 1410);
DISPLAY 0.489362 (-5190 1410);
PAINT MONO (-5190 1410);
FORCEPROP 0 LASTPIN (-5200 1350) $PN CF5
J 0
(-5190 1360);
DISPLAY 0.489362 (-5190 1360);
PAINT MONO (-5190 1360);
FORCEPROP 0 LASTPIN (-5200 1300) $PN CF8
J 0
(-5190 1310);
DISPLAY 0.489362 (-5190 1310);
PAINT MONO (-5190 1310);
FORCEPROP 0 LASTPIN (-5200 1250) $PN CF10
J 0
(-5190 1260);
DISPLAY 0.489362 (-5190 1260);
PAINT MONO (-5190 1260);
FORCEPROP 0 LASTPIN (-5200 1200) $PN CF12
J 0
(-5190 1210);
DISPLAY 0.489362 (-5190 1210);
PAINT MONO (-5190 1210);
FORCEPROP 0 LASTPIN (-5200 1150) $PN CF15
J 0
(-5190 1160);
DISPLAY 0.489362 (-5190 1160);
PAINT MONO (-5190 1160);
FORCEPROP 0 LASTPIN (-5200 1100) $PN CF17
J 0
(-5190 1110);
DISPLAY 0.489362 (-5190 1110);
PAINT MONO (-5190 1110);
FORCEPROP 0 LASTPIN (-5200 1050) $PN CF19
J 0
(-5190 1060);
DISPLAY 0.489362 (-5190 1060);
PAINT MONO (-5190 1060);
FORCEPROP 0 LASTPIN (-5200 1000) $PN CF23
J 0
(-5190 1010);
DISPLAY 0.489362 (-5190 1010);
PAINT MONO (-5190 1010);
FORCEPROP 0 LASTPIN (-5200 950) $PN CF24
J 0
(-5190 960);
DISPLAY 0.489362 (-5190 960);
PAINT MONO (-5190 960);
FORCEPROP 0 LASTPIN (-5200 900) $PN CF25
J 0
(-5190 910);
DISPLAY 0.489362 (-5190 910);
PAINT MONO (-5190 910);
FORCEPROP 0 LASTPIN (-5200 850) $PN CF26
J 0
(-5190 860);
DISPLAY 0.489362 (-5190 860);
PAINT MONO (-5190 860);
FORCEPROP 0 LASTPIN (-5200 800) $PN CF27
J 0
(-5190 810);
DISPLAY 0.489362 (-5190 810);
PAINT MONO (-5190 810);
FORCEPROP 0 LASTPIN (-5200 750) $PN CF28
J 0
(-5190 760);
DISPLAY 0.489362 (-5190 760);
PAINT MONO (-5190 760);
FORCEPROP 0 LASTPIN (-5200 700) $PN CF29
J 0
(-5190 710);
DISPLAY 0.489362 (-5190 710);
PAINT MONO (-5190 710);
FORCEPROP 0 LASTPIN (-5200 650) $PN CF30
J 0
(-5190 660);
DISPLAY 0.489362 (-5190 660);
PAINT MONO (-5190 660);
FORCEPROP 0 LASTPIN (-5200 600) $PN CF31
J 0
(-5190 610);
DISPLAY 0.489362 (-5190 610);
PAINT MONO (-5190 610);
FORCEPROP 0 LASTPIN (-5200 550) $PN CF32
J 0
(-5190 560);
DISPLAY 0.489362 (-5190 560);
PAINT MONO (-5190 560);
FORCEPROP 0 LASTPIN (-5200 500) $PN CF33
J 0
(-5190 510);
DISPLAY 0.489362 (-5190 510);
PAINT MONO (-5190 510);
FORCEPROP 2 LAST PART_TYPE SMLF
J 0
(-6150 6700);
DISPLAY 1.021277 (-6150 6700);
FORCEPROP 1 LAST MATERIAL IO
J 0
(-6145 6532);
DISPLAY 0.489362 (-6145 6532);
PAINT SKYBLUE (-6145 6532);
FORCEPROP 2 LAST VALUE SOCKET6096_13568-001
J 0
(-6150 6575);
DISPLAY 0.489362 (-6150 6575);
PAINT SKYBLUE (-6150 6575);
FORCEPROP 1 LAST PART_NUMBER DGA^6000030
J 0
(-6145 6659);
DISPLAY 0.489362 (-6145 6659);
PAINT SKYBLUE (-6145 6659);
FORCEPROP 1 LAST NEEDS_NO_SIZE TRUE
J 0
(-5750 3450);
DISPLAY 0.723404 (-5750 3450);
PAINT GREEN (-5750 3450);
DISPLAY INVISIBLE (-5750 3450);
FORCEPROP 1 LAST CDS_LMAN_SYM_OUTLINE -400,3050,400,-3050
J 0
(-5750 3450);
DISPLAY 0.468085 (-5750 3450);
PAINT GREEN (-5750 3450);
DISPLAY INVISIBLE (-5750 3450);
FORCEPROP 2 LAST CDS_LIB pure_quanta
J 0
(-5750 3450);
DISPLAY INVISIBLE (-5750 3450);
FORCEPROP 1 LAST PATH I14
J 0
(-5750 3450);
DISPLAY 0.723404 (-5750 3450);
PAINT GREEN (-5750 3450);
DISPLAY INVISIBLE (-5750 3450);
FORCEADD GENOA_SP5..38
(-3675 3425);
FORCEPROP 1 LAST LOCATION U25
J 0
(-4070 6600);
DISPLAY 0.489362 (-4070 6600);
PAINT SKYBLUE (-4070 6600);
FORCEPROP 0 LAST $SEC 38
J 0
(-4050 6825);
DISPLAY 0.680851 (-4050 6825);
PAINT MONO (-4050 6825);
DISPLAY INVISIBLE (-4050 6825);
FORCEPROP 0 LAST CDS_SEC 38
J 0
(-4300 6650);
DISPLAY 1.021277 (-4300 6650);
DISPLAY INVISIBLE (-4300 6650);
FORCEPROP 0 LASTPIN (-4225 6275) $PN CF34
J 2
(-4235 6285);
DISPLAY 0.489362 (-4235 6285);
PAINT MONO (-4235 6285);
FORCEPROP 0 LASTPIN (-4225 6225) $PN CF37
J 2
(-4235 6235);
DISPLAY 0.489362 (-4235 6235);
PAINT MONO (-4235 6235);
FORCEPROP 0 LASTPIN (-4225 6175) $PN CF39
J 2
(-4235 6185);
DISPLAY 0.489362 (-4235 6185);
PAINT MONO (-4235 6185);
FORCEPROP 0 LASTPIN (-4225 6125) $PN CF42
J 2
(-4235 6135);
DISPLAY 0.489362 (-4235 6135);
PAINT MONO (-4235 6135);
FORCEPROP 0 LASTPIN (-4225 6075) $PN CF43
J 2
(-4235 6085);
DISPLAY 0.489362 (-4235 6085);
PAINT MONO (-4235 6085);
FORCEPROP 0 LASTPIN (-4225 6025) $PN CF44
J 2
(-4235 6035);
DISPLAY 0.489362 (-4235 6035);
PAINT MONO (-4235 6035);
FORCEPROP 0 LASTPIN (-4225 5975) $PN CF45
J 2
(-4235 5985);
DISPLAY 0.489362 (-4235 5985);
PAINT MONO (-4235 5985);
FORCEPROP 0 LASTPIN (-4225 5925) $PN CF47
J 2
(-4235 5935);
DISPLAY 0.489362 (-4235 5935);
PAINT MONO (-4235 5935);
FORCEPROP 0 LASTPIN (-4225 5875) $PN CF48
J 2
(-4235 5885);
DISPLAY 0.489362 (-4235 5885);
PAINT MONO (-4235 5885);
FORCEPROP 0 LASTPIN (-4225 5825) $PN CF49
J 2
(-4235 5835);
DISPLAY 0.489362 (-4235 5835);
PAINT MONO (-4235 5835);
FORCEPROP 0 LASTPIN (-4225 5775) $PN CF50
J 2
(-4235 5785);
DISPLAY 0.489362 (-4235 5785);
PAINT MONO (-4235 5785);
FORCEPROP 0 LASTPIN (-4225 5725) $PN CF51
J 2
(-4235 5735);
DISPLAY 0.489362 (-4235 5735);
PAINT MONO (-4235 5735);
FORCEPROP 0 LASTPIN (-4225 5675) $PN CF52
J 2
(-4235 5685);
DISPLAY 0.489362 (-4235 5685);
PAINT MONO (-4235 5685);
FORCEPROP 0 LASTPIN (-4225 5625) $PN CF53
J 2
(-4235 5635);
DISPLAY 0.489362 (-4235 5635);
PAINT MONO (-4235 5635);
FORCEPROP 0 LASTPIN (-4225 5575) $PN CF57
J 2
(-4235 5585);
DISPLAY 0.489362 (-4235 5585);
PAINT MONO (-4235 5585);
FORCEPROP 0 LASTPIN (-4225 5525) $PN CF59
J 2
(-4235 5535);
DISPLAY 0.489362 (-4235 5535);
PAINT MONO (-4235 5535);
FORCEPROP 0 LASTPIN (-4225 5475) $PN CF61
J 2
(-4235 5485);
DISPLAY 0.489362 (-4235 5485);
PAINT MONO (-4235 5485);
FORCEPROP 0 LASTPIN (-4225 5425) $PN CF64
J 2
(-4235 5435);
DISPLAY 0.489362 (-4235 5435);
PAINT MONO (-4235 5435);
FORCEPROP 0 LASTPIN (-4225 5375) $PN CF66
J 2
(-4235 5385);
DISPLAY 0.489362 (-4235 5385);
PAINT MONO (-4235 5385);
FORCEPROP 0 LASTPIN (-4225 5325) $PN CF68
J 2
(-4235 5335);
DISPLAY 0.489362 (-4235 5335);
PAINT MONO (-4235 5335);
FORCEPROP 0 LASTPIN (-4225 5275) $PN CF71
J 2
(-4235 5285);
DISPLAY 0.489362 (-4235 5285);
PAINT MONO (-4235 5285);
FORCEPROP 0 LASTPIN (-4225 5225) $PN CF73
J 2
(-4235 5235);
DISPLAY 0.489362 (-4235 5235);
PAINT MONO (-4235 5235);
FORCEPROP 0 LASTPIN (-4225 5175) $PN CG1
J 2
(-4235 5185);
DISPLAY 0.489362 (-4235 5185);
PAINT MONO (-4235 5185);
FORCEPROP 0 LASTPIN (-4225 5125) $PN CG6
J 2
(-4235 5135);
DISPLAY 0.489362 (-4235 5135);
PAINT MONO (-4235 5135);
FORCEPROP 0 LASTPIN (-4225 5075) $PN CG8
J 2
(-4235 5085);
DISPLAY 0.489362 (-4235 5085);
PAINT MONO (-4235 5085);
FORCEPROP 0 LASTPIN (-4225 5025) $PN CG13
J 2
(-4235 5035);
DISPLAY 0.489362 (-4235 5035);
PAINT MONO (-4235 5035);
FORCEPROP 0 LASTPIN (-4225 4975) $PN CG15
J 2
(-4235 4985);
DISPLAY 0.489362 (-4235 4985);
PAINT MONO (-4235 4985);
FORCEPROP 0 LASTPIN (-4225 4925) $PN CG20
J 2
(-4235 4935);
DISPLAY 0.489362 (-4235 4935);
PAINT MONO (-4235 4935);
FORCEPROP 0 LASTPIN (-4225 4875) $PN CG22
J 2
(-4235 4885);
DISPLAY 0.489362 (-4235 4885);
PAINT MONO (-4235 4885);
FORCEPROP 0 LASTPIN (-4225 4825) $PN CG25
J 2
(-4235 4835);
DISPLAY 0.489362 (-4235 4835);
PAINT MONO (-4235 4835);
FORCEPROP 0 LASTPIN (-4225 4775) $PN CG28
J 2
(-4235 4785);
DISPLAY 0.489362 (-4235 4785);
PAINT MONO (-4235 4785);
FORCEPROP 0 LASTPIN (-4225 4725) $PN CG31
J 2
(-4235 4735);
DISPLAY 0.489362 (-4235 4735);
PAINT MONO (-4235 4735);
FORCEPROP 0 LASTPIN (-4225 4675) $PN CG34
J 2
(-4235 4685);
DISPLAY 0.489362 (-4235 4685);
PAINT MONO (-4235 4685);
FORCEPROP 0 LASTPIN (-4225 4625) $PN CG45
J 2
(-4235 4635);
DISPLAY 0.489362 (-4235 4635);
PAINT MONO (-4235 4635);
FORCEPROP 0 LASTPIN (-4225 4575) $PN CG48
J 2
(-4235 4585);
DISPLAY 0.489362 (-4235 4585);
PAINT MONO (-4235 4585);
FORCEPROP 0 LASTPIN (-4225 4525) $PN CG51
J 2
(-4235 4535);
DISPLAY 0.489362 (-4235 4535);
PAINT MONO (-4235 4535);
FORCEPROP 0 LASTPIN (-4225 4475) $PN CG54
J 2
(-4235 4485);
DISPLAY 0.489362 (-4235 4485);
PAINT MONO (-4235 4485);
FORCEPROP 0 LASTPIN (-4225 4425) $PN CG56
J 2
(-4235 4435);
DISPLAY 0.489362 (-4235 4435);
PAINT MONO (-4235 4435);
FORCEPROP 0 LASTPIN (-4225 4375) $PN CG61
J 2
(-4235 4385);
DISPLAY 0.489362 (-4235 4385);
PAINT MONO (-4235 4385);
FORCEPROP 0 LASTPIN (-4225 4325) $PN CG63
J 2
(-4235 4335);
DISPLAY 0.489362 (-4235 4335);
PAINT MONO (-4235 4335);
FORCEPROP 0 LASTPIN (-4225 4275) $PN CG68
J 2
(-4235 4285);
DISPLAY 0.489362 (-4235 4285);
PAINT MONO (-4235 4285);
FORCEPROP 0 LASTPIN (-4225 4225) $PN CG70
J 2
(-4235 4235);
DISPLAY 0.489362 (-4235 4235);
PAINT MONO (-4235 4235);
FORCEPROP 0 LASTPIN (-4225 4175) $PN CG75
J 2
(-4235 4185);
DISPLAY 0.489362 (-4235 4185);
PAINT MONO (-4235 4185);
FORCEPROP 0 LASTPIN (-4225 4125) $PN CH3
J 2
(-4235 4135);
DISPLAY 0.489362 (-4235 4135);
PAINT MONO (-4235 4135);
FORCEPROP 0 LASTPIN (-4225 4075) $PN CH5
J 2
(-4235 4085);
DISPLAY 0.489362 (-4235 4085);
PAINT MONO (-4235 4085);
FORCEPROP 0 LASTPIN (-4225 4025) $PN CH8
J 2
(-4235 4035);
DISPLAY 0.489362 (-4235 4035);
PAINT MONO (-4235 4035);
FORCEPROP 0 LASTPIN (-4225 3975) $PN CH10
J 2
(-4235 3985);
DISPLAY 0.489362 (-4235 3985);
PAINT MONO (-4235 3985);
FORCEPROP 0 LASTPIN (-4225 3925) $PN CH12
J 2
(-4235 3935);
DISPLAY 0.489362 (-4235 3935);
PAINT MONO (-4235 3935);
FORCEPROP 0 LASTPIN (-4225 3875) $PN CH15
J 2
(-4235 3885);
DISPLAY 0.489362 (-4235 3885);
PAINT MONO (-4235 3885);
FORCEPROP 0 LASTPIN (-4225 3825) $PN CH17
J 2
(-4235 3835);
DISPLAY 0.489362 (-4235 3835);
PAINT MONO (-4235 3835);
FORCEPROP 0 LASTPIN (-4225 3775) $PN CH19
J 2
(-4235 3785);
DISPLAY 0.489362 (-4235 3785);
PAINT MONO (-4235 3785);
FORCEPROP 0 LASTPIN (-4225 3725) $PN CH22
J 2
(-4235 3735);
DISPLAY 0.489362 (-4235 3735);
PAINT MONO (-4235 3735);
FORCEPROP 0 LASTPIN (-4225 3675) $PN CH25
J 2
(-4235 3685);
DISPLAY 0.489362 (-4235 3685);
PAINT MONO (-4235 3685);
FORCEPROP 0 LASTPIN (-4225 3625) $PN CH28
J 2
(-4235 3635);
DISPLAY 0.489362 (-4235 3635);
PAINT MONO (-4235 3635);
FORCEPROP 0 LASTPIN (-4225 3575) $PN CH31
J 2
(-4235 3585);
DISPLAY 0.489362 (-4235 3585);
PAINT MONO (-4235 3585);
FORCEPROP 0 LASTPIN (-4225 3525) $PN CH34
J 2
(-4235 3535);
DISPLAY 0.489362 (-4235 3535);
PAINT MONO (-4235 3535);
FORCEPROP 0 LASTPIN (-4225 3475) $PN CH37
J 2
(-4235 3485);
DISPLAY 0.489362 (-4235 3485);
PAINT MONO (-4235 3485);
FORCEPROP 0 LASTPIN (-4225 3425) $PN CH39
J 2
(-4235 3435);
DISPLAY 0.489362 (-4235 3435);
PAINT MONO (-4235 3435);
FORCEPROP 0 LASTPIN (-4225 3375) $PN CH42
J 2
(-4235 3385);
DISPLAY 0.489362 (-4235 3385);
PAINT MONO (-4235 3385);
FORCEPROP 0 LASTPIN (-4225 3325) $PN CH45
J 2
(-4235 3335);
DISPLAY 0.489362 (-4235 3335);
PAINT MONO (-4235 3335);
FORCEPROP 0 LASTPIN (-4225 3275) $PN CH48
J 2
(-4235 3285);
DISPLAY 0.489362 (-4235 3285);
PAINT MONO (-4235 3285);
FORCEPROP 0 LASTPIN (-4225 3225) $PN CH51
J 2
(-4235 3235);
DISPLAY 0.489362 (-4235 3235);
PAINT MONO (-4235 3235);
FORCEPROP 0 LASTPIN (-4225 3175) $PN CH54
J 2
(-4235 3185);
DISPLAY 0.489362 (-4235 3185);
PAINT MONO (-4235 3185);
FORCEPROP 0 LASTPIN (-4225 3125) $PN CH57
J 2
(-4235 3135);
DISPLAY 0.489362 (-4235 3135);
PAINT MONO (-4235 3135);
FORCEPROP 0 LASTPIN (-4225 3075) $PN CH59
J 2
(-4235 3085);
DISPLAY 0.489362 (-4235 3085);
PAINT MONO (-4235 3085);
FORCEPROP 0 LASTPIN (-4225 3025) $PN CH61
J 2
(-4235 3035);
DISPLAY 0.489362 (-4235 3035);
PAINT MONO (-4235 3035);
FORCEPROP 0 LASTPIN (-4225 2975) $PN CH64
J 2
(-4235 2985);
DISPLAY 0.489362 (-4235 2985);
PAINT MONO (-4235 2985);
FORCEPROP 0 LASTPIN (-4225 2925) $PN CH66
J 2
(-4235 2935);
DISPLAY 0.489362 (-4235 2935);
PAINT MONO (-4235 2935);
FORCEPROP 0 LASTPIN (-4225 2875) $PN CH68
J 2
(-4235 2885);
DISPLAY 0.489362 (-4235 2885);
PAINT MONO (-4235 2885);
FORCEPROP 0 LASTPIN (-4225 2825) $PN CH71
J 2
(-4235 2835);
DISPLAY 0.489362 (-4235 2835);
PAINT MONO (-4235 2835);
FORCEPROP 0 LASTPIN (-4225 2775) $PN CH73
J 2
(-4235 2785);
DISPLAY 0.489362 (-4235 2785);
PAINT MONO (-4235 2785);
FORCEPROP 0 LASTPIN (-4225 2725) $PN CJ1
J 2
(-4235 2735);
DISPLAY 0.489362 (-4235 2735);
PAINT MONO (-4235 2735);
FORCEPROP 0 LASTPIN (-4225 2675) $PN CJ4
J 2
(-4235 2685);
DISPLAY 0.489362 (-4235 2685);
PAINT MONO (-4235 2685);
FORCEPROP 0 LASTPIN (-4225 2625) $PN CJ6
J 2
(-4235 2635);
DISPLAY 0.489362 (-4235 2635);
PAINT MONO (-4235 2635);
FORCEPROP 0 LASTPIN (-4225 2575) $PN CJ8
J 2
(-4235 2585);
DISPLAY 0.489362 (-4235 2585);
PAINT MONO (-4235 2585);
FORCEPROP 0 LASTPIN (-4225 2525) $PN CJ11
J 2
(-4235 2535);
DISPLAY 0.489362 (-4235 2535);
PAINT MONO (-4235 2535);
FORCEPROP 0 LASTPIN (-4225 2475) $PN CJ13
J 2
(-4235 2485);
DISPLAY 0.489362 (-4235 2485);
PAINT MONO (-4235 2485);
FORCEPROP 0 LASTPIN (-4225 2425) $PN CJ15
J 2
(-4235 2435);
DISPLAY 0.489362 (-4235 2435);
PAINT MONO (-4235 2435);
FORCEPROP 0 LASTPIN (-4225 2375) $PN CJ18
J 2
(-4235 2385);
DISPLAY 0.489362 (-4235 2385);
PAINT MONO (-4235 2385);
FORCEPROP 0 LASTPIN (-4225 2325) $PN CJ20
J 2
(-4235 2335);
DISPLAY 0.489362 (-4235 2335);
PAINT MONO (-4235 2335);
FORCEPROP 0 LASTPIN (-4225 2275) $PN CJ23
J 2
(-4235 2285);
DISPLAY 0.489362 (-4235 2285);
PAINT MONO (-4235 2285);
FORCEPROP 0 LASTPIN (-4225 2225) $PN CJ31
J 2
(-4235 2235);
DISPLAY 0.489362 (-4235 2235);
PAINT MONO (-4235 2235);
FORCEPROP 0 LASTPIN (-4225 2175) $PN CJ34
J 2
(-4235 2185);
DISPLAY 0.489362 (-4235 2185);
PAINT MONO (-4235 2185);
FORCEPROP 0 LASTPIN (-4225 2125) $PN CJ35
J 2
(-4235 2135);
DISPLAY 0.489362 (-4235 2135);
PAINT MONO (-4235 2135);
FORCEPROP 0 LASTPIN (-4225 2075) $PN CJ36
J 2
(-4235 2085);
DISPLAY 0.489362 (-4235 2085);
PAINT MONO (-4235 2085);
FORCEPROP 0 LASTPIN (-4225 2025) $PN CJ40
J 2
(-4235 2035);
DISPLAY 0.489362 (-4235 2035);
PAINT MONO (-4235 2035);
FORCEPROP 0 LASTPIN (-4225 1975) $PN CJ41
J 2
(-4235 1985);
DISPLAY 0.489362 (-4235 1985);
PAINT MONO (-4235 1985);
FORCEPROP 0 LASTPIN (-4225 1925) $PN CJ42
J 2
(-4235 1935);
DISPLAY 0.489362 (-4235 1935);
PAINT MONO (-4235 1935);
FORCEPROP 0 LASTPIN (-4225 1875) $PN CJ45
J 2
(-4235 1885);
DISPLAY 0.489362 (-4235 1885);
PAINT MONO (-4235 1885);
FORCEPROP 0 LASTPIN (-4225 1825) $PN CJ56
J 2
(-4235 1835);
DISPLAY 0.489362 (-4235 1835);
PAINT MONO (-4235 1835);
FORCEPROP 0 LASTPIN (-4225 1775) $PN CJ58
J 2
(-4235 1785);
DISPLAY 0.489362 (-4235 1785);
PAINT MONO (-4235 1785);
FORCEPROP 0 LASTPIN (-4225 1725) $PN CJ61
J 2
(-4235 1735);
DISPLAY 0.489362 (-4235 1735);
PAINT MONO (-4235 1735);
FORCEPROP 0 LASTPIN (-4225 1675) $PN CJ63
J 2
(-4235 1685);
DISPLAY 0.489362 (-4235 1685);
PAINT MONO (-4235 1685);
FORCEPROP 0 LASTPIN (-4225 1625) $PN CJ65
J 2
(-4235 1635);
DISPLAY 0.489362 (-4235 1635);
PAINT MONO (-4235 1635);
FORCEPROP 0 LASTPIN (-4225 1575) $PN CJ68
J 2
(-4235 1585);
DISPLAY 0.489362 (-4235 1585);
PAINT MONO (-4235 1585);
FORCEPROP 0 LASTPIN (-4225 1525) $PN CJ70
J 2
(-4235 1535);
DISPLAY 0.489362 (-4235 1535);
PAINT MONO (-4235 1535);
FORCEPROP 0 LASTPIN (-4225 1475) $PN CJ72
J 2
(-4235 1485);
DISPLAY 0.489362 (-4235 1485);
PAINT MONO (-4235 1485);
FORCEPROP 0 LASTPIN (-4225 1425) $PN CJ75
J 2
(-4235 1435);
DISPLAY 0.489362 (-4235 1435);
PAINT MONO (-4235 1435);
FORCEPROP 0 LASTPIN (-4225 1375) $PN CK3
J 2
(-4235 1385);
DISPLAY 0.489362 (-4235 1385);
PAINT MONO (-4235 1385);
FORCEPROP 0 LASTPIN (-4225 1325) $PN CK8
J 2
(-4235 1335);
DISPLAY 0.489362 (-4235 1335);
PAINT MONO (-4235 1335);
FORCEPROP 0 LASTPIN (-4225 1275) $PN CK15
J 2
(-4235 1285);
DISPLAY 0.489362 (-4235 1285);
PAINT MONO (-4235 1285);
FORCEPROP 0 LASTPIN (-4225 1225) $PN CK17
J 2
(-4235 1235);
DISPLAY 0.489362 (-4235 1235);
PAINT MONO (-4235 1235);
FORCEPROP 0 LASTPIN (-4225 1175) $PN CK22
J 2
(-4235 1185);
DISPLAY 0.489362 (-4235 1185);
PAINT MONO (-4235 1185);
FORCEPROP 0 LASTPIN (-4225 1125) $PN CK23
J 2
(-4235 1135);
DISPLAY 0.489362 (-4235 1135);
PAINT MONO (-4235 1135);
FORCEPROP 0 LASTPIN (-4225 1075) $PN CK24
J 2
(-4235 1085);
DISPLAY 0.489362 (-4235 1085);
PAINT MONO (-4235 1085);
FORCEPROP 0 LASTPIN (-4225 1025) $PN CK25
J 2
(-4235 1035);
DISPLAY 0.489362 (-4235 1035);
PAINT MONO (-4235 1035);
FORCEPROP 0 LASTPIN (-4225 975) $PN CK26
J 2
(-4235 985);
DISPLAY 0.489362 (-4235 985);
PAINT MONO (-4235 985);
FORCEPROP 0 LASTPIN (-4225 925) $PN CK27
J 2
(-4235 935);
DISPLAY 0.489362 (-4235 935);
PAINT MONO (-4235 935);
FORCEPROP 0 LASTPIN (-4225 875) $PN CK28
J 2
(-4235 885);
DISPLAY 0.489362 (-4235 885);
PAINT MONO (-4235 885);
FORCEPROP 0 LASTPIN (-4225 825) $PN CK32
J 2
(-4235 835);
DISPLAY 0.489362 (-4235 835);
PAINT MONO (-4235 835);
FORCEPROP 0 LASTPIN (-4225 775) $PN CK33
J 2
(-4235 785);
DISPLAY 0.489362 (-4235 785);
PAINT MONO (-4235 785);
FORCEPROP 0 LASTPIN (-4225 725) $PN CK34
J 2
(-4235 735);
DISPLAY 0.489362 (-4235 735);
PAINT MONO (-4235 735);
FORCEPROP 0 LASTPIN (-4225 675) $PN CK37
J 2
(-4235 685);
DISPLAY 0.489362 (-4235 685);
PAINT MONO (-4235 685);
FORCEPROP 0 LASTPIN (-4225 625) $PN CK39
J 2
(-4235 635);
DISPLAY 0.489362 (-4235 635);
PAINT MONO (-4235 635);
FORCEPROP 0 LASTPIN (-4225 575) $PN CK42
J 2
(-4235 585);
DISPLAY 0.489362 (-4235 585);
PAINT MONO (-4235 585);
FORCEPROP 0 LASTPIN (-3125 6375) $PN CK43
J 0
(-3115 6385);
DISPLAY 0.489362 (-3115 6385);
PAINT MONO (-3115 6385);
FORCEPROP 0 LASTPIN (-3125 6325) $PN CK44
J 0
(-3115 6335);
DISPLAY 0.489362 (-3115 6335);
PAINT MONO (-3115 6335);
FORCEPROP 0 LASTPIN (-3125 6275) $PN CK45
J 0
(-3115 6285);
DISPLAY 0.489362 (-3115 6285);
PAINT MONO (-3115 6285);
FORCEPROP 0 LASTPIN (-3125 6225) $PN CK48
J 0
(-3115 6235);
DISPLAY 0.489362 (-3115 6235);
PAINT MONO (-3115 6235);
FORCEPROP 0 LASTPIN (-3125 6175) $PN CK49
J 0
(-3115 6185);
DISPLAY 0.489362 (-3115 6185);
PAINT MONO (-3115 6185);
FORCEPROP 0 LASTPIN (-3125 6125) $PN CK50
J 0
(-3115 6135);
DISPLAY 0.489362 (-3115 6135);
PAINT MONO (-3115 6135);
FORCEPROP 0 LASTPIN (-3125 6075) $PN CK51
J 0
(-3115 6085);
DISPLAY 0.489362 (-3115 6085);
PAINT MONO (-3115 6085);
FORCEPROP 0 LASTPIN (-3125 6025) $PN CK52
J 0
(-3115 6035);
DISPLAY 0.489362 (-3115 6035);
PAINT MONO (-3115 6035);
FORCEPROP 0 LASTPIN (-3125 5975) $PN CK53
J 0
(-3115 5985);
DISPLAY 0.489362 (-3115 5985);
PAINT MONO (-3115 5985);
FORCEPROP 0 LASTPIN (-3125 5925) $PN CK54
J 0
(-3115 5935);
DISPLAY 0.489362 (-3115 5935);
PAINT MONO (-3115 5935);
FORCEPROP 0 LASTPIN (-3125 5875) $PN CK59
J 0
(-3115 5885);
DISPLAY 0.489362 (-3115 5885);
PAINT MONO (-3115 5885);
FORCEPROP 0 LASTPIN (-3125 5825) $PN CK61
J 0
(-3115 5835);
DISPLAY 0.489362 (-3115 5835);
PAINT MONO (-3115 5835);
FORCEPROP 0 LASTPIN (-3125 5775) $PN CK66
J 0
(-3115 5785);
DISPLAY 0.489362 (-3115 5785);
PAINT MONO (-3115 5785);
FORCEPROP 0 LASTPIN (-3125 5725) $PN CK68
J 0
(-3115 5735);
DISPLAY 0.489362 (-3115 5735);
PAINT MONO (-3115 5735);
FORCEPROP 0 LASTPIN (-3125 5675) $PN CK73
J 0
(-3115 5685);
DISPLAY 0.489362 (-3115 5685);
PAINT MONO (-3115 5685);
FORCEPROP 0 LASTPIN (-3125 5625) $PN CL1
J 0
(-3115 5635);
DISPLAY 0.489362 (-3115 5635);
PAINT MONO (-3115 5635);
FORCEPROP 0 LASTPIN (-3125 5575) $PN CL4
J 0
(-3115 5585);
DISPLAY 0.489362 (-3115 5585);
PAINT MONO (-3115 5585);
FORCEPROP 0 LASTPIN (-3125 5525) $PN CL6
J 0
(-3115 5535);
DISPLAY 0.489362 (-3115 5535);
PAINT MONO (-3115 5535);
FORCEPROP 0 LASTPIN (-3125 5475) $PN CL8
J 0
(-3115 5485);
DISPLAY 0.489362 (-3115 5485);
PAINT MONO (-3115 5485);
FORCEPROP 0 LASTPIN (-3125 5425) $PN CL11
J 0
(-3115 5435);
DISPLAY 0.489362 (-3115 5435);
PAINT MONO (-3115 5435);
FORCEPROP 0 LASTPIN (-3125 5375) $PN CL13
J 0
(-3115 5385);
DISPLAY 0.489362 (-3115 5385);
PAINT MONO (-3115 5385);
FORCEPROP 0 LASTPIN (-3125 5325) $PN CL15
J 0
(-3115 5335);
DISPLAY 0.489362 (-3115 5335);
PAINT MONO (-3115 5335);
FORCEPROP 0 LASTPIN (-3125 5275) $PN CL18
J 0
(-3115 5285);
DISPLAY 0.489362 (-3115 5285);
PAINT MONO (-3115 5285);
FORCEPROP 0 LASTPIN (-3125 5225) $PN CL20
J 0
(-3115 5235);
DISPLAY 0.489362 (-3115 5235);
PAINT MONO (-3115 5235);
FORCEPROP 0 LASTPIN (-3125 5175) $PN CL22
J 0
(-3115 5185);
DISPLAY 0.489362 (-3115 5185);
PAINT MONO (-3115 5185);
FORCEPROP 0 LASTPIN (-3125 5125) $PN CL25
J 0
(-3115 5135);
DISPLAY 0.489362 (-3115 5135);
PAINT MONO (-3115 5135);
FORCEPROP 0 LASTPIN (-3125 5075) $PN CL28
J 0
(-3115 5085);
DISPLAY 0.489362 (-3115 5085);
PAINT MONO (-3115 5085);
FORCEPROP 0 LASTPIN (-3125 5025) $PN CL31
J 0
(-3115 5035);
DISPLAY 0.489362 (-3115 5035);
PAINT MONO (-3115 5035);
FORCEPROP 0 LASTPIN (-3125 4975) $PN CL34
J 0
(-3115 4985);
DISPLAY 0.489362 (-3115 4985);
PAINT MONO (-3115 4985);
FORCEPROP 0 LASTPIN (-3125 4925) $PN CL35
J 0
(-3115 4935);
DISPLAY 0.489362 (-3115 4935);
PAINT MONO (-3115 4935);
FORCEPROP 0 LASTPIN (-3125 4875) $PN CL36
J 0
(-3115 4885);
DISPLAY 0.489362 (-3115 4885);
PAINT MONO (-3115 4885);
FORCEPROP 0 LASTPIN (-3125 4825) $PN CL40
J 0
(-3115 4835);
DISPLAY 0.489362 (-3115 4835);
PAINT MONO (-3115 4835);
FORCEPROP 0 LASTPIN (-3125 4775) $PN CL41
J 0
(-3115 4785);
DISPLAY 0.489362 (-3115 4785);
PAINT MONO (-3115 4785);
FORCEPROP 0 LASTPIN (-3125 4725) $PN CL42
J 0
(-3115 4735);
DISPLAY 0.489362 (-3115 4735);
PAINT MONO (-3115 4735);
FORCEPROP 0 LASTPIN (-3125 4675) $PN CL45
J 0
(-3115 4685);
DISPLAY 0.489362 (-3115 4685);
PAINT MONO (-3115 4685);
FORCEPROP 0 LASTPIN (-3125 4625) $PN CL48
J 0
(-3115 4635);
DISPLAY 0.489362 (-3115 4635);
PAINT MONO (-3115 4635);
FORCEPROP 0 LASTPIN (-3125 4575) $PN CL51
J 0
(-3115 4585);
DISPLAY 0.489362 (-3115 4585);
PAINT MONO (-3115 4585);
FORCEPROP 0 LASTPIN (-3125 4525) $PN CL54
J 0
(-3115 4535);
DISPLAY 0.489362 (-3115 4535);
PAINT MONO (-3115 4535);
FORCEPROP 0 LASTPIN (-3125 4475) $PN CL56
J 0
(-3115 4485);
DISPLAY 0.489362 (-3115 4485);
PAINT MONO (-3115 4485);
FORCEPROP 0 LASTPIN (-3125 4425) $PN CL58
J 0
(-3115 4435);
DISPLAY 0.489362 (-3115 4435);
PAINT MONO (-3115 4435);
FORCEPROP 0 LASTPIN (-3125 4375) $PN CL61
J 0
(-3115 4385);
DISPLAY 0.489362 (-3115 4385);
PAINT MONO (-3115 4385);
FORCEPROP 0 LASTPIN (-3125 4325) $PN CL63
J 0
(-3115 4335);
DISPLAY 0.489362 (-3115 4335);
PAINT MONO (-3115 4335);
FORCEPROP 0 LASTPIN (-3125 4275) $PN CL65
J 0
(-3115 4285);
DISPLAY 0.489362 (-3115 4285);
PAINT MONO (-3115 4285);
FORCEPROP 0 LASTPIN (-3125 4225) $PN CL68
J 0
(-3115 4235);
DISPLAY 0.489362 (-3115 4235);
PAINT MONO (-3115 4235);
FORCEPROP 0 LASTPIN (-3125 4175) $PN CL70
J 0
(-3115 4185);
DISPLAY 0.489362 (-3115 4185);
PAINT MONO (-3115 4185);
FORCEPROP 0 LASTPIN (-3125 4125) $PN CL72
J 0
(-3115 4135);
DISPLAY 0.489362 (-3115 4135);
PAINT MONO (-3115 4135);
FORCEPROP 0 LASTPIN (-3125 4075) $PN CL75
J 0
(-3115 4085);
DISPLAY 0.489362 (-3115 4085);
PAINT MONO (-3115 4085);
FORCEPROP 0 LASTPIN (-3125 4025) $PN CM3
J 0
(-3115 4035);
DISPLAY 0.489362 (-3115 4035);
PAINT MONO (-3115 4035);
FORCEPROP 0 LASTPIN (-3125 3975) $PN CM5
J 0
(-3115 3985);
DISPLAY 0.489362 (-3115 3985);
PAINT MONO (-3115 3985);
FORCEPROP 0 LASTPIN (-3125 3925) $PN CM8
J 0
(-3115 3935);
DISPLAY 0.489362 (-3115 3935);
PAINT MONO (-3115 3935);
FORCEPROP 0 LASTPIN (-3125 3875) $PN CM10
J 0
(-3115 3885);
DISPLAY 0.489362 (-3115 3885);
PAINT MONO (-3115 3885);
FORCEPROP 0 LASTPIN (-3125 3825) $PN CM12
J 0
(-3115 3835);
DISPLAY 0.489362 (-3115 3835);
PAINT MONO (-3115 3835);
FORCEPROP 0 LASTPIN (-3125 3775) $PN CM15
J 0
(-3115 3785);
DISPLAY 0.489362 (-3115 3785);
PAINT MONO (-3115 3785);
FORCEPROP 0 LASTPIN (-3125 3725) $PN CM17
J 0
(-3115 3735);
DISPLAY 0.489362 (-3115 3735);
PAINT MONO (-3115 3735);
FORCEPROP 0 LASTPIN (-3125 3675) $PN CM19
J 0
(-3115 3685);
DISPLAY 0.489362 (-3115 3685);
PAINT MONO (-3115 3685);
FORCEPROP 0 LASTPIN (-3125 3625) $PN CM23
J 0
(-3115 3635);
DISPLAY 0.489362 (-3115 3635);
PAINT MONO (-3115 3635);
FORCEPROP 0 LASTPIN (-3125 3575) $PN CM24
J 0
(-3115 3585);
DISPLAY 0.489362 (-3115 3585);
PAINT MONO (-3115 3585);
FORCEPROP 0 LASTPIN (-3125 3525) $PN CM25
J 0
(-3115 3535);
DISPLAY 0.489362 (-3115 3535);
PAINT MONO (-3115 3535);
FORCEPROP 0 LASTPIN (-3125 3475) $PN CM26
J 0
(-3115 3485);
DISPLAY 0.489362 (-3115 3485);
PAINT MONO (-3115 3485);
FORCEPROP 0 LASTPIN (-3125 3425) $PN CM27
J 0
(-3115 3435);
DISPLAY 0.489362 (-3115 3435);
PAINT MONO (-3115 3435);
FORCEPROP 0 LASTPIN (-3125 3375) $PN CM28
J 0
(-3115 3385);
DISPLAY 0.489362 (-3115 3385);
PAINT MONO (-3115 3385);
FORCEPROP 0 LASTPIN (-3125 3325) $PN CM29
J 0
(-3115 3335);
DISPLAY 0.489362 (-3115 3335);
PAINT MONO (-3115 3335);
FORCEPROP 0 LASTPIN (-3125 3275) $PN CM30
J 0
(-3115 3285);
DISPLAY 0.489362 (-3115 3285);
PAINT MONO (-3115 3285);
FORCEPROP 0 LASTPIN (-3125 3225) $PN CM31
J 0
(-3115 3235);
DISPLAY 0.489362 (-3115 3235);
PAINT MONO (-3115 3235);
FORCEPROP 0 LASTPIN (-3125 3175) $PN CM32
J 0
(-3115 3185);
DISPLAY 0.489362 (-3115 3185);
PAINT MONO (-3115 3185);
FORCEPROP 0 LASTPIN (-3125 3125) $PN CM33
J 0
(-3115 3135);
DISPLAY 0.489362 (-3115 3135);
PAINT MONO (-3115 3135);
FORCEPROP 0 LASTPIN (-3125 3075) $PN CM34
J 0
(-3115 3085);
DISPLAY 0.489362 (-3115 3085);
PAINT MONO (-3115 3085);
FORCEPROP 0 LASTPIN (-3125 3025) $PN CM37
J 0
(-3115 3035);
DISPLAY 0.489362 (-3115 3035);
PAINT MONO (-3115 3035);
FORCEPROP 0 LASTPIN (-3125 2975) $PN CM39
J 0
(-3115 2985);
DISPLAY 0.489362 (-3115 2985);
PAINT MONO (-3115 2985);
FORCEPROP 0 LASTPIN (-3125 2925) $PN CM42
J 0
(-3115 2935);
DISPLAY 0.489362 (-3115 2935);
PAINT MONO (-3115 2935);
FORCEPROP 0 LASTPIN (-3125 2875) $PN CM43
J 0
(-3115 2885);
DISPLAY 0.489362 (-3115 2885);
PAINT MONO (-3115 2885);
FORCEPROP 0 LASTPIN (-3125 2825) $PN CM44
J 0
(-3115 2835);
DISPLAY 0.489362 (-3115 2835);
PAINT MONO (-3115 2835);
FORCEPROP 0 LASTPIN (-3125 2775) $PN CM45
J 0
(-3115 2785);
DISPLAY 0.489362 (-3115 2785);
PAINT MONO (-3115 2785);
FORCEPROP 0 LASTPIN (-3125 2725) $PN CM46
J 0
(-3115 2735);
DISPLAY 0.489362 (-3115 2735);
PAINT MONO (-3115 2735);
FORCEPROP 0 LASTPIN (-3125 2675) $PN CM47
J 0
(-3115 2685);
DISPLAY 0.489362 (-3115 2685);
PAINT MONO (-3115 2685);
FORCEPROP 0 LASTPIN (-3125 2625) $PN CM48
J 0
(-3115 2635);
DISPLAY 0.489362 (-3115 2635);
PAINT MONO (-3115 2635);
FORCEPROP 0 LASTPIN (-3125 2575) $PN CM49
J 0
(-3115 2585);
DISPLAY 0.489362 (-3115 2585);
PAINT MONO (-3115 2585);
FORCEPROP 0 LASTPIN (-3125 2525) $PN CM51
J 0
(-3115 2535);
DISPLAY 0.489362 (-3115 2535);
PAINT MONO (-3115 2535);
FORCEPROP 0 LASTPIN (-3125 2475) $PN CM52
J 0
(-3115 2485);
DISPLAY 0.489362 (-3115 2485);
PAINT MONO (-3115 2485);
FORCEPROP 0 LASTPIN (-3125 2425) $PN CM53
J 0
(-3115 2435);
DISPLAY 0.489362 (-3115 2435);
PAINT MONO (-3115 2435);
FORCEPROP 0 LASTPIN (-3125 2375) $PN CM57
J 0
(-3115 2385);
DISPLAY 0.489362 (-3115 2385);
PAINT MONO (-3115 2385);
FORCEPROP 0 LASTPIN (-3125 2325) $PN CM59
J 0
(-3115 2335);
DISPLAY 0.489362 (-3115 2335);
PAINT MONO (-3115 2335);
FORCEPROP 0 LASTPIN (-3125 2275) $PN CM61
J 0
(-3115 2285);
DISPLAY 0.489362 (-3115 2285);
PAINT MONO (-3115 2285);
FORCEPROP 0 LASTPIN (-3125 2225) $PN CM64
J 0
(-3115 2235);
DISPLAY 0.489362 (-3115 2235);
PAINT MONO (-3115 2235);
FORCEPROP 0 LASTPIN (-3125 2175) $PN CM66
J 0
(-3115 2185);
DISPLAY 0.489362 (-3115 2185);
PAINT MONO (-3115 2185);
FORCEPROP 0 LASTPIN (-3125 2125) $PN CM68
J 0
(-3115 2135);
DISPLAY 0.489362 (-3115 2135);
PAINT MONO (-3115 2135);
FORCEPROP 0 LASTPIN (-3125 2075) $PN CM71
J 0
(-3115 2085);
DISPLAY 0.489362 (-3115 2085);
PAINT MONO (-3115 2085);
FORCEPROP 0 LASTPIN (-3125 2025) $PN CM73
J 0
(-3115 2035);
DISPLAY 0.489362 (-3115 2035);
PAINT MONO (-3115 2035);
FORCEPROP 0 LASTPIN (-3125 1975) $PN CN1
J 0
(-3115 1985);
DISPLAY 0.489362 (-3115 1985);
PAINT MONO (-3115 1985);
FORCEPROP 0 LASTPIN (-3125 1925) $PN CN6
J 0
(-3115 1935);
DISPLAY 0.489362 (-3115 1935);
PAINT MONO (-3115 1935);
FORCEPROP 0 LASTPIN (-3125 1875) $PN CN8
J 0
(-3115 1885);
DISPLAY 0.489362 (-3115 1885);
PAINT MONO (-3115 1885);
FORCEPROP 0 LASTPIN (-3125 1825) $PN CN13
J 0
(-3115 1835);
DISPLAY 0.489362 (-3115 1835);
PAINT MONO (-3115 1835);
FORCEPROP 0 LASTPIN (-3125 1775) $PN CN15
J 0
(-3115 1785);
DISPLAY 0.489362 (-3115 1785);
PAINT MONO (-3115 1785);
FORCEPROP 0 LASTPIN (-3125 1725) $PN CN20
J 0
(-3115 1735);
DISPLAY 0.489362 (-3115 1735);
PAINT MONO (-3115 1735);
FORCEPROP 0 LASTPIN (-3125 1675) $PN CN22
J 0
(-3115 1685);
DISPLAY 0.489362 (-3115 1685);
PAINT MONO (-3115 1685);
FORCEPROP 0 LASTPIN (-3125 1625) $PN CN25
J 0
(-3115 1635);
DISPLAY 0.489362 (-3115 1635);
PAINT MONO (-3115 1635);
FORCEPROP 0 LASTPIN (-3125 1575) $PN CN28
J 0
(-3115 1585);
DISPLAY 0.489362 (-3115 1585);
PAINT MONO (-3115 1585);
FORCEPROP 0 LASTPIN (-3125 1525) $PN CN31
J 0
(-3115 1535);
DISPLAY 0.489362 (-3115 1535);
PAINT MONO (-3115 1535);
FORCEPROP 0 LASTPIN (-3125 1475) $PN CN34
J 0
(-3115 1485);
DISPLAY 0.489362 (-3115 1485);
PAINT MONO (-3115 1485);
FORCEPROP 0 LASTPIN (-3125 1425) $PN CN42
J 0
(-3115 1435);
DISPLAY 0.489362 (-3115 1435);
PAINT MONO (-3115 1435);
FORCEPROP 0 LASTPIN (-3125 1375) $PN CN45
J 0
(-3115 1385);
DISPLAY 0.489362 (-3115 1385);
PAINT MONO (-3115 1385);
FORCEPROP 0 LASTPIN (-3125 1325) $PN CN48
J 0
(-3115 1335);
DISPLAY 0.489362 (-3115 1335);
PAINT MONO (-3115 1335);
FORCEPROP 0 LASTPIN (-3125 1275) $PN CN51
J 0
(-3115 1285);
DISPLAY 0.489362 (-3115 1285);
PAINT MONO (-3115 1285);
FORCEPROP 0 LASTPIN (-3125 1225) $PN CN56
J 0
(-3115 1235);
DISPLAY 0.489362 (-3115 1235);
PAINT MONO (-3115 1235);
FORCEPROP 0 LASTPIN (-3125 1175) $PN CN61
J 0
(-3115 1185);
DISPLAY 0.489362 (-3115 1185);
PAINT MONO (-3115 1185);
FORCEPROP 0 LASTPIN (-3125 1125) $PN CN63
J 0
(-3115 1135);
DISPLAY 0.489362 (-3115 1135);
PAINT MONO (-3115 1135);
FORCEPROP 0 LASTPIN (-3125 1075) $PN CN68
J 0
(-3115 1085);
DISPLAY 0.489362 (-3115 1085);
PAINT MONO (-3115 1085);
FORCEPROP 0 LASTPIN (-3125 1025) $PN CN70
J 0
(-3115 1035);
DISPLAY 0.489362 (-3115 1035);
PAINT MONO (-3115 1035);
FORCEPROP 0 LASTPIN (-3125 975) $PN CN75
J 0
(-3115 985);
DISPLAY 0.489362 (-3115 985);
PAINT MONO (-3115 985);
FORCEPROP 0 LASTPIN (-3125 925) $PN CP3
J 0
(-3115 935);
DISPLAY 0.489362 (-3115 935);
PAINT MONO (-3115 935);
FORCEPROP 0 LASTPIN (-3125 875) $PN CP5
J 0
(-3115 885);
DISPLAY 0.489362 (-3115 885);
PAINT MONO (-3115 885);
FORCEPROP 0 LASTPIN (-3125 825) $PN CP8
J 0
(-3115 835);
DISPLAY 0.489362 (-3115 835);
PAINT MONO (-3115 835);
FORCEPROP 0 LASTPIN (-3125 775) $PN CP10
J 0
(-3115 785);
DISPLAY 0.489362 (-3115 785);
PAINT MONO (-3115 785);
FORCEPROP 0 LASTPIN (-3125 725) $PN CP12
J 0
(-3115 735);
DISPLAY 0.489362 (-3115 735);
PAINT MONO (-3115 735);
FORCEPROP 0 LASTPIN (-3125 675) $PN CP15
J 0
(-3115 685);
DISPLAY 0.489362 (-3115 685);
PAINT MONO (-3115 685);
FORCEPROP 0 LASTPIN (-3125 625) $PN CP17
J 0
(-3115 635);
DISPLAY 0.489362 (-3115 635);
PAINT MONO (-3115 635);
FORCEPROP 0 LASTPIN (-3125 575) $PN CP19
J 0
(-3115 585);
DISPLAY 0.489362 (-3115 585);
PAINT MONO (-3115 585);
FORCEPROP 2 LAST PART_TYPE SMLF
J 0
(-4075 6675);
DISPLAY 1.021277 (-4075 6675);
FORCEPROP 1 LAST MATERIAL IO
J 0
(-4070 6507);
DISPLAY 0.489362 (-4070 6507);
PAINT SKYBLUE (-4070 6507);
FORCEPROP 2 LAST VALUE SOCKET6096_13568-001
J 0
(-4075 6550);
DISPLAY 0.489362 (-4075 6550);
PAINT SKYBLUE (-4075 6550);
FORCEPROP 1 LAST PART_NUMBER DGA^6000030
J 0
(-4070 6634);
DISPLAY 0.489362 (-4070 6634);
PAINT SKYBLUE (-4070 6634);
FORCEPROP 1 LAST NEEDS_NO_SIZE TRUE
J 0
(-3675 3425);
DISPLAY 0.723404 (-3675 3425);
PAINT GREEN (-3675 3425);
DISPLAY INVISIBLE (-3675 3425);
FORCEPROP 1 LAST CDS_LMAN_SYM_OUTLINE -400,3050,400,-3050
J 0
(-3675 3425);
DISPLAY 0.468085 (-3675 3425);
PAINT GREEN (-3675 3425);
DISPLAY INVISIBLE (-3675 3425);
FORCEPROP 2 LAST CDS_LIB pure_quanta
J 0
(-3675 3425);
DISPLAY INVISIBLE (-3675 3425);
FORCEPROP 1 LAST PATH I15
J 0
(-3675 3425);
DISPLAY 0.723404 (-3675 3425);
PAINT GREEN (-3675 3425);
DISPLAY INVISIBLE (-3675 3425);
FORCEADD GENOA_SP5..39
(-1600 3450);
FORCEPROP 1 LAST LOCATION U25
J 0
(-1995 6600);
DISPLAY 0.489362 (-1995 6600);
PAINT SKYBLUE (-1995 6600);
FORCEPROP 0 LAST $SEC 39
J 0
(-1975 6850);
DISPLAY 0.680851 (-1975 6850);
PAINT MONO (-1975 6850);
DISPLAY INVISIBLE (-1975 6850);
FORCEPROP 0 LAST CDS_SEC 39
J 0
(-2225 6700);
DISPLAY 1.021277 (-2225 6700);
DISPLAY INVISIBLE (-2225 6700);
FORCEPROP 0 LASTPIN (-1050 500) $PN CP22
J 0
(-1040 510);
DISPLAY 0.489362 (-1040 510);
PAINT MONO (-1040 510);
FORCEPROP 0 LASTPIN (-1050 550) $PN CP25
J 0
(-1040 560);
DISPLAY 0.489362 (-1040 560);
PAINT MONO (-1040 560);
FORCEPROP 0 LASTPIN (-1050 600) $PN CP28
J 0
(-1040 610);
DISPLAY 0.489362 (-1040 610);
PAINT MONO (-1040 610);
FORCEPROP 0 LASTPIN (-1050 650) $PN CP31
J 0
(-1040 660);
DISPLAY 0.489362 (-1040 660);
PAINT MONO (-1040 660);
FORCEPROP 0 LASTPIN (-1050 700) $PN CP34
J 0
(-1040 710);
DISPLAY 0.489362 (-1040 710);
PAINT MONO (-1040 710);
FORCEPROP 0 LASTPIN (-1050 750) $PN CP37
J 0
(-1040 760);
DISPLAY 0.489362 (-1040 760);
PAINT MONO (-1040 760);
FORCEPROP 0 LASTPIN (-1050 800) $PN CP39
J 0
(-1040 810);
DISPLAY 0.489362 (-1040 810);
PAINT MONO (-1040 810);
FORCEPROP 0 LASTPIN (-1050 850) $PN CP42
J 0
(-1040 860);
DISPLAY 0.489362 (-1040 860);
PAINT MONO (-1040 860);
FORCEPROP 0 LASTPIN (-1050 900) $PN CP45
J 0
(-1040 910);
DISPLAY 0.489362 (-1040 910);
PAINT MONO (-1040 910);
FORCEPROP 0 LASTPIN (-1050 950) $PN CP48
J 0
(-1040 960);
DISPLAY 0.489362 (-1040 960);
PAINT MONO (-1040 960);
FORCEPROP 0 LASTPIN (-1050 1000) $PN CP51
J 0
(-1040 1010);
DISPLAY 0.489362 (-1040 1010);
PAINT MONO (-1040 1010);
FORCEPROP 0 LASTPIN (-1050 1050) $PN CP54
J 0
(-1040 1060);
DISPLAY 0.489362 (-1040 1060);
PAINT MONO (-1040 1060);
FORCEPROP 0 LASTPIN (-1050 1100) $PN CP57
J 0
(-1040 1110);
DISPLAY 0.489362 (-1040 1110);
PAINT MONO (-1040 1110);
FORCEPROP 0 LASTPIN (-1050 1150) $PN CP59
J 0
(-1040 1160);
DISPLAY 0.489362 (-1040 1160);
PAINT MONO (-1040 1160);
FORCEPROP 0 LASTPIN (-1050 1200) $PN CP61
J 0
(-1040 1210);
DISPLAY 0.489362 (-1040 1210);
PAINT MONO (-1040 1210);
FORCEPROP 0 LASTPIN (-1050 1250) $PN CP64
J 0
(-1040 1260);
DISPLAY 0.489362 (-1040 1260);
PAINT MONO (-1040 1260);
FORCEPROP 0 LASTPIN (-1050 1300) $PN CP66
J 0
(-1040 1310);
DISPLAY 0.489362 (-1040 1310);
PAINT MONO (-1040 1310);
FORCEPROP 0 LASTPIN (-1050 1350) $PN CP68
J 0
(-1040 1360);
DISPLAY 0.489362 (-1040 1360);
PAINT MONO (-1040 1360);
FORCEPROP 0 LASTPIN (-1050 1400) $PN CP71
J 0
(-1040 1410);
DISPLAY 0.489362 (-1040 1410);
PAINT MONO (-1040 1410);
FORCEPROP 0 LASTPIN (-1050 1450) $PN CP73
J 0
(-1040 1460);
DISPLAY 0.489362 (-1040 1460);
PAINT MONO (-1040 1460);
FORCEPROP 0 LASTPIN (-1050 1500) $PN CR1
J 0
(-1040 1510);
DISPLAY 0.489362 (-1040 1510);
PAINT MONO (-1040 1510);
FORCEPROP 0 LASTPIN (-1050 1550) $PN CR4
J 0
(-1040 1560);
DISPLAY 0.489362 (-1040 1560);
PAINT MONO (-1040 1560);
FORCEPROP 0 LASTPIN (-1050 1600) $PN CR6
J 0
(-1040 1610);
DISPLAY 0.489362 (-1040 1610);
PAINT MONO (-1040 1610);
FORCEPROP 0 LASTPIN (-1050 1650) $PN CR8
J 0
(-1040 1660);
DISPLAY 0.489362 (-1040 1660);
PAINT MONO (-1040 1660);
FORCEPROP 0 LASTPIN (-1050 1700) $PN CR11
J 0
(-1040 1710);
DISPLAY 0.489362 (-1040 1710);
PAINT MONO (-1040 1710);
FORCEPROP 0 LASTPIN (-1050 1750) $PN CR13
J 0
(-1040 1760);
DISPLAY 0.489362 (-1040 1760);
PAINT MONO (-1040 1760);
FORCEPROP 0 LASTPIN (-1050 1800) $PN CR15
J 0
(-1040 1810);
DISPLAY 0.489362 (-1040 1810);
PAINT MONO (-1040 1810);
FORCEPROP 0 LASTPIN (-1050 1850) $PN CR18
J 0
(-1040 1860);
DISPLAY 0.489362 (-1040 1860);
PAINT MONO (-1040 1860);
FORCEPROP 0 LASTPIN (-1050 1900) $PN CR20
J 0
(-1040 1910);
DISPLAY 0.489362 (-1040 1910);
PAINT MONO (-1040 1910);
FORCEPROP 0 LASTPIN (-1050 1950) $PN CR22
J 0
(-1040 1960);
DISPLAY 0.489362 (-1040 1960);
PAINT MONO (-1040 1960);
FORCEPROP 0 LASTPIN (-1050 2000) $PN CR25
J 0
(-1040 2010);
DISPLAY 0.489362 (-1040 2010);
PAINT MONO (-1040 2010);
FORCEPROP 0 LASTPIN (-1050 2050) $PN CR28
J 0
(-1040 2060);
DISPLAY 0.489362 (-1040 2060);
PAINT MONO (-1040 2060);
FORCEPROP 0 LASTPIN (-1050 2100) $PN CR31
J 0
(-1040 2110);
DISPLAY 0.489362 (-1040 2110);
PAINT MONO (-1040 2110);
FORCEPROP 0 LASTPIN (-1050 2150) $PN CR34
J 0
(-1040 2160);
DISPLAY 0.489362 (-1040 2160);
PAINT MONO (-1040 2160);
FORCEPROP 0 LASTPIN (-1050 2200) $PN CR35
J 0
(-1040 2210);
DISPLAY 0.489362 (-1040 2210);
PAINT MONO (-1040 2210);
FORCEPROP 0 LASTPIN (-1050 2250) $PN CR36
J 0
(-1040 2260);
DISPLAY 0.489362 (-1040 2260);
PAINT MONO (-1040 2260);
FORCEPROP 0 LASTPIN (-1050 2300) $PN CR40
J 0
(-1040 2310);
DISPLAY 0.489362 (-1040 2310);
PAINT MONO (-1040 2310);
FORCEPROP 0 LASTPIN (-1050 2350) $PN CR41
J 0
(-1040 2360);
DISPLAY 0.489362 (-1040 2360);
PAINT MONO (-1040 2360);
FORCEPROP 0 LASTPIN (-1050 2400) $PN CR42
J 0
(-1040 2410);
DISPLAY 0.489362 (-1040 2410);
PAINT MONO (-1040 2410);
FORCEPROP 0 LASTPIN (-1050 2450) $PN CR45
J 0
(-1040 2460);
DISPLAY 0.489362 (-1040 2460);
PAINT MONO (-1040 2460);
FORCEPROP 0 LASTPIN (-1050 2500) $PN CR48
J 0
(-1040 2510);
DISPLAY 0.489362 (-1040 2510);
PAINT MONO (-1040 2510);
FORCEPROP 0 LASTPIN (-1050 2550) $PN CR51
J 0
(-1040 2560);
DISPLAY 0.489362 (-1040 2560);
PAINT MONO (-1040 2560);
FORCEPROP 0 LASTPIN (-1050 2600) $PN CR54
J 0
(-1040 2610);
DISPLAY 0.489362 (-1040 2610);
PAINT MONO (-1040 2610);
FORCEPROP 0 LASTPIN (-1050 2650) $PN CR56
J 0
(-1040 2660);
DISPLAY 0.489362 (-1040 2660);
PAINT MONO (-1040 2660);
FORCEPROP 0 LASTPIN (-1050 2700) $PN CR58
J 0
(-1040 2710);
DISPLAY 0.489362 (-1040 2710);
PAINT MONO (-1040 2710);
FORCEPROP 0 LASTPIN (-1050 2750) $PN CR61
J 0
(-1040 2760);
DISPLAY 0.489362 (-1040 2760);
PAINT MONO (-1040 2760);
FORCEPROP 0 LASTPIN (-1050 2800) $PN CR63
J 0
(-1040 2810);
DISPLAY 0.489362 (-1040 2810);
PAINT MONO (-1040 2810);
FORCEPROP 0 LASTPIN (-1050 2850) $PN CR65
J 0
(-1040 2860);
DISPLAY 0.489362 (-1040 2860);
PAINT MONO (-1040 2860);
FORCEPROP 0 LASTPIN (-1050 2900) $PN CR68
J 0
(-1040 2910);
DISPLAY 0.489362 (-1040 2910);
PAINT MONO (-1040 2910);
FORCEPROP 0 LASTPIN (-1050 2950) $PN CR70
J 0
(-1040 2960);
DISPLAY 0.489362 (-1040 2960);
PAINT MONO (-1040 2960);
FORCEPROP 0 LASTPIN (-1050 3000) $PN CR72
J 0
(-1040 3010);
DISPLAY 0.489362 (-1040 3010);
PAINT MONO (-1040 3010);
FORCEPROP 0 LASTPIN (-1050 3050) $PN CR75
J 0
(-1040 3060);
DISPLAY 0.489362 (-1040 3060);
PAINT MONO (-1040 3060);
FORCEPROP 0 LASTPIN (-1050 3100) $PN CT3
J 0
(-1040 3110);
DISPLAY 0.489362 (-1040 3110);
PAINT MONO (-1040 3110);
FORCEPROP 0 LASTPIN (-1050 3150) $PN CT8
J 0
(-1040 3160);
DISPLAY 0.489362 (-1040 3160);
PAINT MONO (-1040 3160);
FORCEPROP 0 LASTPIN (-1050 3200) $PN CT10
J 0
(-1040 3210);
DISPLAY 0.489362 (-1040 3210);
PAINT MONO (-1040 3210);
FORCEPROP 0 LASTPIN (-1050 3250) $PN CT15
J 0
(-1040 3260);
DISPLAY 0.489362 (-1040 3260);
PAINT MONO (-1040 3260);
FORCEPROP 0 LASTPIN (-1050 3300) $PN CT17
J 0
(-1040 3310);
DISPLAY 0.489362 (-1040 3310);
PAINT MONO (-1040 3310);
FORCEPROP 0 LASTPIN (-1050 3350) $PN CT23
J 0
(-1040 3360);
DISPLAY 0.489362 (-1040 3360);
PAINT MONO (-1040 3360);
FORCEPROP 0 LASTPIN (-1050 3400) $PN CT24
J 0
(-1040 3410);
DISPLAY 0.489362 (-1040 3410);
PAINT MONO (-1040 3410);
FORCEPROP 0 LASTPIN (-1050 3450) $PN CT25
J 0
(-1040 3460);
DISPLAY 0.489362 (-1040 3460);
PAINT MONO (-1040 3460);
FORCEPROP 0 LASTPIN (-1050 3500) $PN CT26
J 0
(-1040 3510);
DISPLAY 0.489362 (-1040 3510);
PAINT MONO (-1040 3510);
FORCEPROP 0 LASTPIN (-1050 3550) $PN CT27
J 0
(-1040 3560);
DISPLAY 0.489362 (-1040 3560);
PAINT MONO (-1040 3560);
FORCEPROP 0 LASTPIN (-1050 3600) $PN CT28
J 0
(-1040 3610);
DISPLAY 0.489362 (-1040 3610);
PAINT MONO (-1040 3610);
FORCEPROP 0 LASTPIN (-1050 3650) $PN CT29
J 0
(-1040 3660);
DISPLAY 0.489362 (-1040 3660);
PAINT MONO (-1040 3660);
FORCEPROP 0 LASTPIN (-1050 3700) $PN CT30
J 0
(-1040 3710);
DISPLAY 0.489362 (-1040 3710);
PAINT MONO (-1040 3710);
FORCEPROP 0 LASTPIN (-1050 3750) $PN CT31
J 0
(-1040 3760);
DISPLAY 0.489362 (-1040 3760);
PAINT MONO (-1040 3760);
FORCEPROP 0 LASTPIN (-1050 3800) $PN CT32
J 0
(-1040 3810);
DISPLAY 0.489362 (-1040 3810);
PAINT MONO (-1040 3810);
FORCEPROP 0 LASTPIN (-1050 3850) $PN CT33
J 0
(-1040 3860);
DISPLAY 0.489362 (-1040 3860);
PAINT MONO (-1040 3860);
FORCEPROP 0 LASTPIN (-1050 3900) $PN CT34
J 0
(-1040 3910);
DISPLAY 0.489362 (-1040 3910);
PAINT MONO (-1040 3910);
FORCEPROP 0 LASTPIN (-1050 3950) $PN CT37
J 0
(-1040 3960);
DISPLAY 0.489362 (-1040 3960);
PAINT MONO (-1040 3960);
FORCEPROP 0 LASTPIN (-1050 4000) $PN CT39
J 0
(-1040 4010);
DISPLAY 0.489362 (-1040 4010);
PAINT MONO (-1040 4010);
FORCEPROP 0 LASTPIN (-1050 4050) $PN CT42
J 0
(-1040 4060);
DISPLAY 0.489362 (-1040 4060);
PAINT MONO (-1040 4060);
FORCEPROP 0 LASTPIN (-1050 4100) $PN CT43
J 0
(-1040 4110);
DISPLAY 0.489362 (-1040 4110);
PAINT MONO (-1040 4110);
FORCEPROP 0 LASTPIN (-1050 4150) $PN CT44
J 0
(-1040 4160);
DISPLAY 0.489362 (-1040 4160);
PAINT MONO (-1040 4160);
FORCEPROP 0 LASTPIN (-1050 4200) $PN CT45
J 0
(-1040 4210);
DISPLAY 0.489362 (-1040 4210);
PAINT MONO (-1040 4210);
FORCEPROP 0 LASTPIN (-1050 4250) $PN CT46
J 0
(-1040 4260);
DISPLAY 0.489362 (-1040 4260);
PAINT MONO (-1040 4260);
FORCEPROP 0 LASTPIN (-1050 4300) $PN CT47
J 0
(-1040 4310);
DISPLAY 0.489362 (-1040 4310);
PAINT MONO (-1040 4310);
FORCEPROP 0 LASTPIN (-1050 4350) $PN CT48
J 0
(-1040 4360);
DISPLAY 0.489362 (-1040 4360);
PAINT MONO (-1040 4360);
FORCEPROP 0 LASTPIN (-1050 4400) $PN CT49
J 0
(-1040 4410);
DISPLAY 0.489362 (-1040 4410);
PAINT MONO (-1040 4410);
FORCEPROP 0 LASTPIN (-1050 4450) $PN CT50
J 0
(-1040 4460);
DISPLAY 0.489362 (-1040 4460);
PAINT MONO (-1040 4460);
FORCEPROP 0 LASTPIN (-1050 4500) $PN CT51
J 0
(-1040 4510);
DISPLAY 0.489362 (-1040 4510);
PAINT MONO (-1040 4510);
FORCEPROP 0 LASTPIN (-1050 4550) $PN CT53
J 0
(-1040 4560);
DISPLAY 0.489362 (-1040 4560);
PAINT MONO (-1040 4560);
FORCEPROP 0 LASTPIN (-1050 4600) $PN CT59
J 0
(-1040 4610);
DISPLAY 0.489362 (-1040 4610);
PAINT MONO (-1040 4610);
FORCEPROP 0 LASTPIN (-1050 4650) $PN CT61
J 0
(-1040 4660);
DISPLAY 0.489362 (-1040 4660);
PAINT MONO (-1040 4660);
FORCEPROP 0 LASTPIN (-1050 4700) $PN CT66
J 0
(-1040 4710);
DISPLAY 0.489362 (-1040 4710);
PAINT MONO (-1040 4710);
FORCEPROP 0 LASTPIN (-1050 4750) $PN CT68
J 0
(-1040 4760);
DISPLAY 0.489362 (-1040 4760);
PAINT MONO (-1040 4760);
FORCEPROP 0 LASTPIN (-1050 4800) $PN CT73
J 0
(-1040 4810);
DISPLAY 0.489362 (-1040 4810);
PAINT MONO (-1040 4810);
FORCEPROP 0 LASTPIN (-1050 4850) $PN CU1
J 0
(-1040 4860);
DISPLAY 0.489362 (-1040 4860);
PAINT MONO (-1040 4860);
FORCEPROP 0 LASTPIN (-1050 4900) $PN CU4
J 0
(-1040 4910);
DISPLAY 0.489362 (-1040 4910);
PAINT MONO (-1040 4910);
FORCEPROP 0 LASTPIN (-1050 4950) $PN CU6
J 0
(-1040 4960);
DISPLAY 0.489362 (-1040 4960);
PAINT MONO (-1040 4960);
FORCEPROP 0 LASTPIN (-1050 5000) $PN CU8
J 0
(-1040 5010);
DISPLAY 0.489362 (-1040 5010);
PAINT MONO (-1040 5010);
FORCEPROP 0 LASTPIN (-1050 5050) $PN CU11
J 0
(-1040 5060);
DISPLAY 0.489362 (-1040 5060);
PAINT MONO (-1040 5060);
FORCEPROP 0 LASTPIN (-1050 5100) $PN CU13
J 0
(-1040 5110);
DISPLAY 0.489362 (-1040 5110);
PAINT MONO (-1040 5110);
FORCEPROP 0 LASTPIN (-1050 5150) $PN CU15
J 0
(-1040 5160);
DISPLAY 0.489362 (-1040 5160);
PAINT MONO (-1040 5160);
FORCEPROP 0 LASTPIN (-1050 5200) $PN CU18
J 0
(-1040 5210);
DISPLAY 0.489362 (-1040 5210);
PAINT MONO (-1040 5210);
FORCEPROP 0 LASTPIN (-1050 5250) $PN CU20
J 0
(-1040 5260);
DISPLAY 0.489362 (-1040 5260);
PAINT MONO (-1040 5260);
FORCEPROP 0 LASTPIN (-1050 5300) $PN CU22
J 0
(-1040 5310);
DISPLAY 0.489362 (-1040 5310);
PAINT MONO (-1040 5310);
FORCEPROP 0 LASTPIN (-1050 5350) $PN CU25
J 0
(-1040 5360);
DISPLAY 0.489362 (-1040 5360);
PAINT MONO (-1040 5360);
FORCEPROP 0 LASTPIN (-1050 5400) $PN CU28
J 0
(-1040 5410);
DISPLAY 0.489362 (-1040 5410);
PAINT MONO (-1040 5410);
FORCEPROP 0 LASTPIN (-1050 5450) $PN CU31
J 0
(-1040 5460);
DISPLAY 0.489362 (-1040 5460);
PAINT MONO (-1040 5460);
FORCEPROP 0 LASTPIN (-1050 5500) $PN CU34
J 0
(-1040 5510);
DISPLAY 0.489362 (-1040 5510);
PAINT MONO (-1040 5510);
FORCEPROP 0 LASTPIN (-1050 5550) $PN CU42
J 0
(-1040 5560);
DISPLAY 0.489362 (-1040 5560);
PAINT MONO (-1040 5560);
FORCEPROP 0 LASTPIN (-1050 5600) $PN CU45
J 0
(-1040 5610);
DISPLAY 0.489362 (-1040 5610);
PAINT MONO (-1040 5610);
FORCEPROP 0 LASTPIN (-1050 5650) $PN CU48
J 0
(-1040 5660);
DISPLAY 0.489362 (-1040 5660);
PAINT MONO (-1040 5660);
FORCEPROP 0 LASTPIN (-1050 5700) $PN CU51
J 0
(-1040 5710);
DISPLAY 0.489362 (-1040 5710);
PAINT MONO (-1040 5710);
FORCEPROP 0 LASTPIN (-1050 5750) $PN CU54
J 0
(-1040 5760);
DISPLAY 0.489362 (-1040 5760);
PAINT MONO (-1040 5760);
FORCEPROP 0 LASTPIN (-1050 5800) $PN CU56
J 0
(-1040 5810);
DISPLAY 0.489362 (-1040 5810);
PAINT MONO (-1040 5810);
FORCEPROP 0 LASTPIN (-1050 5850) $PN CU61
J 0
(-1040 5860);
DISPLAY 0.489362 (-1040 5860);
PAINT MONO (-1040 5860);
FORCEPROP 0 LASTPIN (-1050 5900) $PN CU63
J 0
(-1040 5910);
DISPLAY 0.489362 (-1040 5910);
PAINT MONO (-1040 5910);
FORCEPROP 0 LASTPIN (-1050 5950) $PN CU65
J 0
(-1040 5960);
DISPLAY 0.489362 (-1040 5960);
PAINT MONO (-1040 5960);
FORCEPROP 0 LASTPIN (-1050 6000) $PN CU68
J 0
(-1040 6010);
DISPLAY 0.489362 (-1040 6010);
PAINT MONO (-1040 6010);
FORCEPROP 0 LASTPIN (-1050 6050) $PN CU70
J 0
(-1040 6060);
DISPLAY 0.489362 (-1040 6060);
PAINT MONO (-1040 6060);
FORCEPROP 0 LASTPIN (-1050 6100) $PN CU72
J 0
(-1040 6110);
DISPLAY 0.489362 (-1040 6110);
PAINT MONO (-1040 6110);
FORCEPROP 0 LASTPIN (-1050 6150) $PN CU75
J 0
(-1040 6160);
DISPLAY 0.489362 (-1040 6160);
PAINT MONO (-1040 6160);
FORCEPROP 0 LASTPIN (-1050 6200) $PN CV3
J 0
(-1040 6210);
DISPLAY 0.489362 (-1040 6210);
PAINT MONO (-1040 6210);
FORCEPROP 0 LASTPIN (-1050 6250) $PN CV5
J 0
(-1040 6260);
DISPLAY 0.489362 (-1040 6260);
PAINT MONO (-1040 6260);
FORCEPROP 0 LASTPIN (-1050 6300) $PN CV8
J 0
(-1040 6310);
DISPLAY 0.489362 (-1040 6310);
PAINT MONO (-1040 6310);
FORCEPROP 0 LASTPIN (-2150 500) $PN CV10
J 2
(-2160 510);
DISPLAY 0.489362 (-2160 510);
PAINT MONO (-2160 510);
FORCEPROP 0 LASTPIN (-2150 550) $PN CV12
J 2
(-2160 560);
DISPLAY 0.489362 (-2160 560);
PAINT MONO (-2160 560);
FORCEPROP 0 LASTPIN (-2150 600) $PN CV15
J 2
(-2160 610);
DISPLAY 0.489362 (-2160 610);
PAINT MONO (-2160 610);
FORCEPROP 0 LASTPIN (-2150 650) $PN CV17
J 2
(-2160 660);
DISPLAY 0.489362 (-2160 660);
PAINT MONO (-2160 660);
FORCEPROP 0 LASTPIN (-2150 700) $PN CV19
J 2
(-2160 710);
DISPLAY 0.489362 (-2160 710);
PAINT MONO (-2160 710);
FORCEPROP 0 LASTPIN (-2150 750) $PN CV22
J 2
(-2160 760);
DISPLAY 0.489362 (-2160 760);
PAINT MONO (-2160 760);
FORCEPROP 0 LASTPIN (-2150 800) $PN CV25
J 2
(-2160 810);
DISPLAY 0.489362 (-2160 810);
PAINT MONO (-2160 810);
FORCEPROP 0 LASTPIN (-2150 850) $PN CV28
J 2
(-2160 860);
DISPLAY 0.489362 (-2160 860);
PAINT MONO (-2160 860);
FORCEPROP 0 LASTPIN (-2150 900) $PN CV31
J 2
(-2160 910);
DISPLAY 0.489362 (-2160 910);
PAINT MONO (-2160 910);
FORCEPROP 0 LASTPIN (-2150 950) $PN CV34
J 2
(-2160 960);
DISPLAY 0.489362 (-2160 960);
PAINT MONO (-2160 960);
FORCEPROP 0 LASTPIN (-2150 1000) $PN CV37
J 2
(-2160 1010);
DISPLAY 0.489362 (-2160 1010);
PAINT MONO (-2160 1010);
FORCEPROP 0 LASTPIN (-2150 1050) $PN CV39
J 2
(-2160 1060);
DISPLAY 0.489362 (-2160 1060);
PAINT MONO (-2160 1060);
FORCEPROP 0 LASTPIN (-2150 1100) $PN CV42
J 2
(-2160 1110);
DISPLAY 0.489362 (-2160 1110);
PAINT MONO (-2160 1110);
FORCEPROP 0 LASTPIN (-2150 1150) $PN CV45
J 2
(-2160 1160);
DISPLAY 0.489362 (-2160 1160);
PAINT MONO (-2160 1160);
FORCEPROP 0 LASTPIN (-2150 1200) $PN CV48
J 2
(-2160 1210);
DISPLAY 0.489362 (-2160 1210);
PAINT MONO (-2160 1210);
FORCEPROP 0 LASTPIN (-2150 1250) $PN CV51
J 2
(-2160 1260);
DISPLAY 0.489362 (-2160 1260);
PAINT MONO (-2160 1260);
FORCEPROP 0 LASTPIN (-2150 1300) $PN CV54
J 2
(-2160 1310);
DISPLAY 0.489362 (-2160 1310);
PAINT MONO (-2160 1310);
FORCEPROP 0 LASTPIN (-2150 1350) $PN CV57
J 2
(-2160 1360);
DISPLAY 0.489362 (-2160 1360);
PAINT MONO (-2160 1360);
FORCEPROP 0 LASTPIN (-2150 1400) $PN CV59
J 2
(-2160 1410);
DISPLAY 0.489362 (-2160 1410);
PAINT MONO (-2160 1410);
FORCEPROP 0 LASTPIN (-2150 1450) $PN CV61
J 2
(-2160 1460);
DISPLAY 0.489362 (-2160 1460);
PAINT MONO (-2160 1460);
FORCEPROP 0 LASTPIN (-2150 1500) $PN CV64
J 2
(-2160 1510);
DISPLAY 0.489362 (-2160 1510);
PAINT MONO (-2160 1510);
FORCEPROP 0 LASTPIN (-2150 1550) $PN CV66
J 2
(-2160 1560);
DISPLAY 0.489362 (-2160 1560);
PAINT MONO (-2160 1560);
FORCEPROP 0 LASTPIN (-2150 1600) $PN CV68
J 2
(-2160 1610);
DISPLAY 0.489362 (-2160 1610);
PAINT MONO (-2160 1610);
FORCEPROP 0 LASTPIN (-2150 1650) $PN CV71
J 2
(-2160 1660);
DISPLAY 0.489362 (-2160 1660);
PAINT MONO (-2160 1660);
FORCEPROP 0 LASTPIN (-2150 1700) $PN CV73
J 2
(-2160 1710);
DISPLAY 0.489362 (-2160 1710);
PAINT MONO (-2160 1710);
FORCEPROP 0 LASTPIN (-2150 1750) $PN CW1
J 2
(-2160 1760);
DISPLAY 0.489362 (-2160 1760);
PAINT MONO (-2160 1760);
FORCEPROP 0 LASTPIN (-2150 1800) $PN CW6
J 2
(-2160 1810);
DISPLAY 0.489362 (-2160 1810);
PAINT MONO (-2160 1810);
FORCEPROP 0 LASTPIN (-2150 1850) $PN CW8
J 2
(-2160 1860);
DISPLAY 0.489362 (-2160 1860);
PAINT MONO (-2160 1860);
FORCEPROP 0 LASTPIN (-2150 1900) $PN CW13
J 2
(-2160 1910);
DISPLAY 0.489362 (-2160 1910);
PAINT MONO (-2160 1910);
FORCEPROP 0 LASTPIN (-2150 1950) $PN CW15
J 2
(-2160 1960);
DISPLAY 0.489362 (-2160 1960);
PAINT MONO (-2160 1960);
FORCEPROP 0 LASTPIN (-2150 2000) $PN CW20
J 2
(-2160 2010);
DISPLAY 0.489362 (-2160 2010);
PAINT MONO (-2160 2010);
FORCEPROP 0 LASTPIN (-2150 2050) $PN CW22
J 2
(-2160 2060);
DISPLAY 0.489362 (-2160 2060);
PAINT MONO (-2160 2060);
FORCEPROP 0 LASTPIN (-2150 2100) $PN CW25
J 2
(-2160 2110);
DISPLAY 0.489362 (-2160 2110);
PAINT MONO (-2160 2110);
FORCEPROP 0 LASTPIN (-2150 2150) $PN CW28
J 2
(-2160 2160);
DISPLAY 0.489362 (-2160 2160);
PAINT MONO (-2160 2160);
FORCEPROP 0 LASTPIN (-2150 2200) $PN CW31
J 2
(-2160 2210);
DISPLAY 0.489362 (-2160 2210);
PAINT MONO (-2160 2210);
FORCEPROP 0 LASTPIN (-2150 2250) $PN CW34
J 2
(-2160 2260);
DISPLAY 0.489362 (-2160 2260);
PAINT MONO (-2160 2260);
FORCEPROP 0 LASTPIN (-2150 2300) $PN CW35
J 2
(-2160 2310);
DISPLAY 0.489362 (-2160 2310);
PAINT MONO (-2160 2310);
FORCEPROP 0 LASTPIN (-2150 2350) $PN CW36
J 2
(-2160 2360);
DISPLAY 0.489362 (-2160 2360);
PAINT MONO (-2160 2360);
FORCEPROP 0 LASTPIN (-2150 2400) $PN CW40
J 2
(-2160 2410);
DISPLAY 0.489362 (-2160 2410);
PAINT MONO (-2160 2410);
FORCEPROP 0 LASTPIN (-2150 2450) $PN CW41
J 2
(-2160 2460);
DISPLAY 0.489362 (-2160 2460);
PAINT MONO (-2160 2460);
FORCEPROP 0 LASTPIN (-2150 2500) $PN CW42
J 2
(-2160 2510);
DISPLAY 0.489362 (-2160 2510);
PAINT MONO (-2160 2510);
FORCEPROP 0 LASTPIN (-2150 2550) $PN CW45
J 2
(-2160 2560);
DISPLAY 0.489362 (-2160 2560);
PAINT MONO (-2160 2560);
FORCEPROP 0 LASTPIN (-2150 2600) $PN CW48
J 2
(-2160 2610);
DISPLAY 0.489362 (-2160 2610);
PAINT MONO (-2160 2610);
FORCEPROP 0 LASTPIN (-2150 2650) $PN CW51
J 2
(-2160 2660);
DISPLAY 0.489362 (-2160 2660);
PAINT MONO (-2160 2660);
FORCEPROP 0 LASTPIN (-2150 2700) $PN CW54
J 2
(-2160 2710);
DISPLAY 0.489362 (-2160 2710);
PAINT MONO (-2160 2710);
FORCEPROP 0 LASTPIN (-2150 2750) $PN CW56
J 2
(-2160 2760);
DISPLAY 0.489362 (-2160 2760);
PAINT MONO (-2160 2760);
FORCEPROP 0 LASTPIN (-2150 2800) $PN CW61
J 2
(-2160 2810);
DISPLAY 0.489362 (-2160 2810);
PAINT MONO (-2160 2810);
FORCEPROP 0 LASTPIN (-2150 2850) $PN CW63
J 2
(-2160 2860);
DISPLAY 0.489362 (-2160 2860);
PAINT MONO (-2160 2860);
FORCEPROP 0 LASTPIN (-2150 2900) $PN CW68
J 2
(-2160 2910);
DISPLAY 0.489362 (-2160 2910);
PAINT MONO (-2160 2910);
FORCEPROP 0 LASTPIN (-2150 2950) $PN CW70
J 2
(-2160 2960);
DISPLAY 0.489362 (-2160 2960);
PAINT MONO (-2160 2960);
FORCEPROP 0 LASTPIN (-2150 3000) $PN CW75
J 2
(-2160 3010);
DISPLAY 0.489362 (-2160 3010);
PAINT MONO (-2160 3010);
FORCEPROP 0 LASTPIN (-2150 3050) $PN CY3
J 2
(-2160 3060);
DISPLAY 0.489362 (-2160 3060);
PAINT MONO (-2160 3060);
FORCEPROP 0 LASTPIN (-2150 3100) $PN CY5
J 2
(-2160 3110);
DISPLAY 0.489362 (-2160 3110);
PAINT MONO (-2160 3110);
FORCEPROP 0 LASTPIN (-2150 3150) $PN CY8
J 2
(-2160 3160);
DISPLAY 0.489362 (-2160 3160);
PAINT MONO (-2160 3160);
FORCEPROP 0 LASTPIN (-2150 3200) $PN CY10
J 2
(-2160 3210);
DISPLAY 0.489362 (-2160 3210);
PAINT MONO (-2160 3210);
FORCEPROP 0 LASTPIN (-2150 3250) $PN CY12
J 2
(-2160 3260);
DISPLAY 0.489362 (-2160 3260);
PAINT MONO (-2160 3260);
FORCEPROP 0 LASTPIN (-2150 3300) $PN CY15
J 2
(-2160 3310);
DISPLAY 0.489362 (-2160 3310);
PAINT MONO (-2160 3310);
FORCEPROP 0 LASTPIN (-2150 3350) $PN CY17
J 2
(-2160 3360);
DISPLAY 0.489362 (-2160 3360);
PAINT MONO (-2160 3360);
FORCEPROP 0 LASTPIN (-2150 3400) $PN CY19
J 2
(-2160 3410);
DISPLAY 0.489362 (-2160 3410);
PAINT MONO (-2160 3410);
FORCEPROP 0 LASTPIN (-2150 3450) $PN CY23
J 2
(-2160 3460);
DISPLAY 0.489362 (-2160 3460);
PAINT MONO (-2160 3460);
FORCEPROP 0 LASTPIN (-2150 3500) $PN CY24
J 2
(-2160 3510);
DISPLAY 0.489362 (-2160 3510);
PAINT MONO (-2160 3510);
FORCEPROP 0 LASTPIN (-2150 3550) $PN CY25
J 2
(-2160 3560);
DISPLAY 0.489362 (-2160 3560);
PAINT MONO (-2160 3560);
FORCEPROP 0 LASTPIN (-2150 3600) $PN CY26
J 2
(-2160 3610);
DISPLAY 0.489362 (-2160 3610);
PAINT MONO (-2160 3610);
FORCEPROP 0 LASTPIN (-2150 3650) $PN CY27
J 2
(-2160 3660);
DISPLAY 0.489362 (-2160 3660);
PAINT MONO (-2160 3660);
FORCEPROP 0 LASTPIN (-2150 3700) $PN CY28
J 2
(-2160 3710);
DISPLAY 0.489362 (-2160 3710);
PAINT MONO (-2160 3710);
FORCEPROP 0 LASTPIN (-2150 3750) $PN CY29
J 2
(-2160 3760);
DISPLAY 0.489362 (-2160 3760);
PAINT MONO (-2160 3760);
FORCEPROP 0 LASTPIN (-2150 3800) $PN CY30
J 2
(-2160 3810);
DISPLAY 0.489362 (-2160 3810);
PAINT MONO (-2160 3810);
FORCEPROP 0 LASTPIN (-2150 3850) $PN CY31
J 2
(-2160 3860);
DISPLAY 0.489362 (-2160 3860);
PAINT MONO (-2160 3860);
FORCEPROP 0 LASTPIN (-2150 3900) $PN CY32
J 2
(-2160 3910);
DISPLAY 0.489362 (-2160 3910);
PAINT MONO (-2160 3910);
FORCEPROP 0 LASTPIN (-2150 3950) $PN CY33
J 2
(-2160 3960);
DISPLAY 0.489362 (-2160 3960);
PAINT MONO (-2160 3960);
FORCEPROP 0 LASTPIN (-2150 4000) $PN CY34
J 2
(-2160 4010);
DISPLAY 0.489362 (-2160 4010);
PAINT MONO (-2160 4010);
FORCEPROP 0 LASTPIN (-2150 4050) $PN CY37
J 2
(-2160 4060);
DISPLAY 0.489362 (-2160 4060);
PAINT MONO (-2160 4060);
FORCEPROP 0 LASTPIN (-2150 4100) $PN CY39
J 2
(-2160 4110);
DISPLAY 0.489362 (-2160 4110);
PAINT MONO (-2160 4110);
FORCEPROP 0 LASTPIN (-2150 4150) $PN CY42
J 2
(-2160 4160);
DISPLAY 0.489362 (-2160 4160);
PAINT MONO (-2160 4160);
FORCEPROP 0 LASTPIN (-2150 4200) $PN CY43
J 2
(-2160 4210);
DISPLAY 0.489362 (-2160 4210);
PAINT MONO (-2160 4210);
FORCEPROP 0 LASTPIN (-2150 4250) $PN CY44
J 2
(-2160 4260);
DISPLAY 0.489362 (-2160 4260);
PAINT MONO (-2160 4260);
FORCEPROP 0 LASTPIN (-2150 4300) $PN CY45
J 2
(-2160 4310);
DISPLAY 0.489362 (-2160 4310);
PAINT MONO (-2160 4310);
FORCEPROP 0 LASTPIN (-2150 4350) $PN CY46
J 2
(-2160 4360);
DISPLAY 0.489362 (-2160 4360);
PAINT MONO (-2160 4360);
FORCEPROP 0 LASTPIN (-2150 4400) $PN CY47
J 2
(-2160 4410);
DISPLAY 0.489362 (-2160 4410);
PAINT MONO (-2160 4410);
FORCEPROP 0 LASTPIN (-2150 4450) $PN CY48
J 2
(-2160 4460);
DISPLAY 0.489362 (-2160 4460);
PAINT MONO (-2160 4460);
FORCEPROP 0 LASTPIN (-2150 4500) $PN CY49
J 2
(-2160 4510);
DISPLAY 0.489362 (-2160 4510);
PAINT MONO (-2160 4510);
FORCEPROP 0 LASTPIN (-2150 4550) $PN CY50
J 2
(-2160 4560);
DISPLAY 0.489362 (-2160 4560);
PAINT MONO (-2160 4560);
FORCEPROP 0 LASTPIN (-2150 4600) $PN CY51
J 2
(-2160 4610);
DISPLAY 0.489362 (-2160 4610);
PAINT MONO (-2160 4610);
FORCEPROP 0 LASTPIN (-2150 4650) $PN CY52
J 2
(-2160 4660);
DISPLAY 0.489362 (-2160 4660);
PAINT MONO (-2160 4660);
FORCEPROP 0 LASTPIN (-2150 4700) $PN CY53
J 2
(-2160 4710);
DISPLAY 0.489362 (-2160 4710);
PAINT MONO (-2160 4710);
FORCEPROP 0 LASTPIN (-2150 4750) $PN CY59
J 2
(-2160 4760);
DISPLAY 0.489362 (-2160 4760);
PAINT MONO (-2160 4760);
FORCEPROP 0 LASTPIN (-2150 4800) $PN CY61
J 2
(-2160 4810);
DISPLAY 0.489362 (-2160 4810);
PAINT MONO (-2160 4810);
FORCEPROP 0 LASTPIN (-2150 4850) $PN CY64
J 2
(-2160 4860);
DISPLAY 0.489362 (-2160 4860);
PAINT MONO (-2160 4860);
FORCEPROP 0 LASTPIN (-2150 4900) $PN CY66
J 2
(-2160 4910);
DISPLAY 0.489362 (-2160 4910);
PAINT MONO (-2160 4910);
FORCEPROP 0 LASTPIN (-2150 4950) $PN CY68
J 2
(-2160 4960);
DISPLAY 0.489362 (-2160 4960);
PAINT MONO (-2160 4960);
FORCEPROP 0 LASTPIN (-2150 5000) $PN CY71
J 2
(-2160 5010);
DISPLAY 0.489362 (-2160 5010);
PAINT MONO (-2160 5010);
FORCEPROP 0 LASTPIN (-2150 5050) $PN CY73
J 2
(-2160 5060);
DISPLAY 0.489362 (-2160 5060);
PAINT MONO (-2160 5060);
FORCEPROP 0 LASTPIN (-2150 5100) $PN DA1
J 2
(-2160 5110);
DISPLAY 0.489362 (-2160 5110);
PAINT MONO (-2160 5110);
FORCEPROP 0 LASTPIN (-2150 5150) $PN DA4
J 2
(-2160 5160);
DISPLAY 0.489362 (-2160 5160);
PAINT MONO (-2160 5160);
FORCEPROP 0 LASTPIN (-2150 5200) $PN DA6
J 2
(-2160 5210);
DISPLAY 0.489362 (-2160 5210);
PAINT MONO (-2160 5210);
FORCEPROP 0 LASTPIN (-2150 5250) $PN DA8
J 2
(-2160 5260);
DISPLAY 0.489362 (-2160 5260);
PAINT MONO (-2160 5260);
FORCEPROP 0 LASTPIN (-2150 5300) $PN DA11
J 2
(-2160 5310);
DISPLAY 0.489362 (-2160 5310);
PAINT MONO (-2160 5310);
FORCEPROP 0 LASTPIN (-2150 5350) $PN DA13
J 2
(-2160 5360);
DISPLAY 0.489362 (-2160 5360);
PAINT MONO (-2160 5360);
FORCEPROP 0 LASTPIN (-2150 5400) $PN DA15
J 2
(-2160 5410);
DISPLAY 0.489362 (-2160 5410);
PAINT MONO (-2160 5410);
FORCEPROP 0 LASTPIN (-2150 5450) $PN DA18
J 2
(-2160 5460);
DISPLAY 0.489362 (-2160 5460);
PAINT MONO (-2160 5460);
FORCEPROP 0 LASTPIN (-2150 5500) $PN DA20
J 2
(-2160 5510);
DISPLAY 0.489362 (-2160 5510);
PAINT MONO (-2160 5510);
FORCEPROP 0 LASTPIN (-2150 5550) $PN DA22
J 2
(-2160 5560);
DISPLAY 0.489362 (-2160 5560);
PAINT MONO (-2160 5560);
FORCEPROP 0 LASTPIN (-2150 5600) $PN DA25
J 2
(-2160 5610);
DISPLAY 0.489362 (-2160 5610);
PAINT MONO (-2160 5610);
FORCEPROP 0 LASTPIN (-2150 5650) $PN DA28
J 2
(-2160 5660);
DISPLAY 0.489362 (-2160 5660);
PAINT MONO (-2160 5660);
FORCEPROP 0 LASTPIN (-2150 5700) $PN DA31
J 2
(-2160 5710);
DISPLAY 0.489362 (-2160 5710);
PAINT MONO (-2160 5710);
FORCEPROP 0 LASTPIN (-2150 5750) $PN DA34
J 2
(-2160 5760);
DISPLAY 0.489362 (-2160 5760);
PAINT MONO (-2160 5760);
FORCEPROP 0 LASTPIN (-2150 5800) $PN DA42
J 2
(-2160 5810);
DISPLAY 0.489362 (-2160 5810);
PAINT MONO (-2160 5810);
FORCEPROP 0 LASTPIN (-2150 5850) $PN DA45
J 2
(-2160 5860);
DISPLAY 0.489362 (-2160 5860);
PAINT MONO (-2160 5860);
FORCEPROP 0 LASTPIN (-2150 5900) $PN DA48
J 2
(-2160 5910);
DISPLAY 0.489362 (-2160 5910);
PAINT MONO (-2160 5910);
FORCEPROP 0 LASTPIN (-2150 5950) $PN DA51
J 2
(-2160 5960);
DISPLAY 0.489362 (-2160 5960);
PAINT MONO (-2160 5960);
FORCEPROP 0 LASTPIN (-2150 6000) $PN DA54
J 2
(-2160 6010);
DISPLAY 0.489362 (-2160 6010);
PAINT MONO (-2160 6010);
FORCEPROP 0 LASTPIN (-2150 6050) $PN DA58
J 2
(-2160 6060);
DISPLAY 0.489362 (-2160 6060);
PAINT MONO (-2160 6060);
FORCEPROP 0 LASTPIN (-2150 6100) $PN DA61
J 2
(-2160 6110);
DISPLAY 0.489362 (-2160 6110);
PAINT MONO (-2160 6110);
FORCEPROP 0 LASTPIN (-2150 6150) $PN DA63
J 2
(-2160 6160);
DISPLAY 0.489362 (-2160 6160);
PAINT MONO (-2160 6160);
FORCEPROP 0 LASTPIN (-2150 6200) $PN DA65
J 2
(-2160 6210);
DISPLAY 0.489362 (-2160 6210);
PAINT MONO (-2160 6210);
FORCEPROP 0 LASTPIN (-2150 6250) $PN DA68
J 2
(-2160 6260);
DISPLAY 0.489362 (-2160 6260);
PAINT MONO (-2160 6260);
FORCEPROP 0 LASTPIN (-2150 6300) $PN DA70
J 2
(-2160 6310);
DISPLAY 0.489362 (-2160 6310);
PAINT MONO (-2160 6310);
FORCEPROP 2 LAST PART_TYPE SMLF
J 0
(-2000 6700);
DISPLAY 1.021277 (-2000 6700);
FORCEPROP 1 LAST MATERIAL IO
J 0
(-1995 6532);
DISPLAY 0.489362 (-1995 6532);
PAINT SKYBLUE (-1995 6532);
FORCEPROP 2 LAST VALUE SOCKET6096_13568-001
J 0
(-2000 6575);
DISPLAY 0.489362 (-2000 6575);
PAINT SKYBLUE (-2000 6575);
FORCEPROP 1 LAST PART_NUMBER DGA^6000030
J 0
(-1995 6659);
DISPLAY 0.489362 (-1995 6659);
PAINT SKYBLUE (-1995 6659);
FORCEPROP 1 LAST NEEDS_NO_SIZE TRUE
J 0
(-1600 3450);
DISPLAY 0.723404 (-1600 3450);
PAINT GREEN (-1600 3450);
DISPLAY INVISIBLE (-1600 3450);
FORCEPROP 1 LAST CDS_LMAN_SYM_OUTLINE -400,3050,400,-3050
J 0
(-1600 3450);
DISPLAY 0.468085 (-1600 3450);
PAINT GREEN (-1600 3450);
DISPLAY INVISIBLE (-1600 3450);
FORCEPROP 2 LAST CDS_LIB pure_quanta
J 0
(-1600 3450);
DISPLAY INVISIBLE (-1600 3450);
FORCEPROP 1 LAST PATH I16
J 0
(-1600 3450);
DISPLAY 0.723404 (-1600 3450);
PAINT GREEN (-1600 3450);
DISPLAY INVISIBLE (-1600 3450);
FORCEADD UNIVERSAL_GND..1
(-7050 425);
FORCEPROP 3 LASTPIN (-7050 475) SIG_NAME GND\g
J 0
(-7040 485);
DISPLAY 0.659574 (-7040 485);
PAINT MONO (-7040 485);
DISPLAY INVISIBLE (-7040 485);
FORCEPROP 2 LAST CDS_LIB pure_quanta_power
J 0
(-7050 425);
DISPLAY INVISIBLE (-7050 425);
FORCEPROP 1 LAST PATH I17
J 0
(-6975 425);
DISPLAY 0.872340 (-6975 425);
PAINT AQUA (-6975 425);
DISPLAY INVISIBLE (-6975 425);
FORCEPROP 1 LAST HDL_POWER GND
J 1
(-7025 350);
DISPLAY 0.872340 (-7025 350);
PAINT GREEN (-7025 350);
DISPLAY INVISIBLE (-7025 350);
FORCEADD UNIVERSAL_GND..1
(-8500 400);
FORCEPROP 3 LASTPIN (-8500 450) SIG_NAME GND\g
J 0
(-8490 460);
DISPLAY 0.659574 (-8490 460);
PAINT MONO (-8490 460);
DISPLAY INVISIBLE (-8490 460);
FORCEPROP 2 LAST CDS_LIB pure_quanta_power
J 0
(-8500 400);
DISPLAY INVISIBLE (-8500 400);
FORCEPROP 1 LAST PATH I18
J 0
(-8425 400);
DISPLAY 0.872340 (-8425 400);
PAINT AQUA (-8425 400);
DISPLAY INVISIBLE (-8425 400);
FORCEPROP 1 LAST HDL_POWER GND
J 1
(-8475 325);
DISPLAY 0.872340 (-8475 325);
PAINT GREEN (-8475 325);
DISPLAY INVISIBLE (-8475 325);
FORCEADD UNIVERSAL_GND..1
(-6475 425);
FORCEPROP 3 LASTPIN (-6475 475) SIG_NAME GND\g
J 0
(-6465 485);
DISPLAY 0.659574 (-6465 485);
PAINT MONO (-6465 485);
DISPLAY INVISIBLE (-6465 485);
FORCEPROP 2 LAST CDS_LIB pure_quanta_power
J 0
(-6475 425);
DISPLAY INVISIBLE (-6475 425);
FORCEPROP 1 LAST PATH I19
J 0
(-6400 425);
DISPLAY 0.872340 (-6400 425);
PAINT AQUA (-6400 425);
DISPLAY INVISIBLE (-6400 425);
FORCEPROP 1 LAST HDL_POWER GND
J 1
(-6450 350);
DISPLAY 0.872340 (-6450 350);
PAINT GREEN (-6450 350);
DISPLAY INVISIBLE (-6450 350);
FORCEADD UNIVERSAL_GND..1
(-5025 425);
FORCEPROP 3 LASTPIN (-5025 475) SIG_NAME GND\g
J 0
(-5015 485);
DISPLAY 0.659574 (-5015 485);
PAINT MONO (-5015 485);
DISPLAY INVISIBLE (-5015 485);
FORCEPROP 2 LAST CDS_LIB pure_quanta_power
J 0
(-5025 425);
DISPLAY INVISIBLE (-5025 425);
FORCEPROP 1 LAST PATH I20
J 0
(-4950 425);
DISPLAY 0.872340 (-4950 425);
PAINT AQUA (-4950 425);
DISPLAY INVISIBLE (-4950 425);
FORCEPROP 1 LAST HDL_POWER GND
J 1
(-5000 350);
DISPLAY 0.872340 (-5000 350);
PAINT GREEN (-5000 350);
DISPLAY INVISIBLE (-5000 350);
FORCEADD UNIVERSAL_GND..1
(-4400 425);
FORCEPROP 3 LASTPIN (-4400 475) SIG_NAME GND\g
J 0
(-4390 485);
DISPLAY 0.659574 (-4390 485);
PAINT MONO (-4390 485);
DISPLAY INVISIBLE (-4390 485);
FORCEPROP 2 LAST CDS_LIB pure_quanta_power
J 0
(-4400 425);
DISPLAY INVISIBLE (-4400 425);
FORCEPROP 1 LAST PATH I21
J 0
(-4325 425);
DISPLAY 0.872340 (-4325 425);
PAINT AQUA (-4325 425);
DISPLAY INVISIBLE (-4325 425);
FORCEPROP 1 LAST HDL_POWER GND
J 1
(-4375 350);
DISPLAY 0.872340 (-4375 350);
PAINT GREEN (-4375 350);
DISPLAY INVISIBLE (-4375 350);
FORCEADD UNIVERSAL_GND..1
(-2950 400);
FORCEPROP 3 LASTPIN (-2950 450) SIG_NAME GND\g
J 0
(-2940 460);
DISPLAY 0.659574 (-2940 460);
PAINT MONO (-2940 460);
DISPLAY INVISIBLE (-2940 460);
FORCEPROP 2 LAST CDS_LIB pure_quanta_power
J 0
(-2950 400);
DISPLAY INVISIBLE (-2950 400);
FORCEPROP 1 LAST PATH I22
J 0
(-2875 400);
DISPLAY 0.872340 (-2875 400);
PAINT AQUA (-2875 400);
DISPLAY INVISIBLE (-2875 400);
FORCEPROP 1 LAST HDL_POWER GND
J 1
(-2925 325);
DISPLAY 0.872340 (-2925 325);
PAINT GREEN (-2925 325);
DISPLAY INVISIBLE (-2925 325);
FORCEADD UNIVERSAL_GND..1
(-875 400);
FORCEPROP 3 LASTPIN (-875 450) SIG_NAME GND\g
J 0
(-865 460);
DISPLAY 0.659574 (-865 460);
PAINT MONO (-865 460);
DISPLAY INVISIBLE (-865 460);
FORCEPROP 2 LAST CDS_LIB pure_quanta_power
J 0
(-875 400);
DISPLAY INVISIBLE (-875 400);
FORCEPROP 1 LAST PATH I23
J 0
(-800 400);
DISPLAY 0.872340 (-800 400);
PAINT AQUA (-800 400);
DISPLAY INVISIBLE (-800 400);
FORCEPROP 1 LAST HDL_POWER GND
J 1
(-850 325);
DISPLAY 0.872340 (-850 325);
PAINT GREEN (-850 325);
DISPLAY INVISIBLE (-850 325);
FORCEADD UNIVERSAL_GND..1
(-2325 400);
FORCEPROP 3 LASTPIN (-2325 450) SIG_NAME GND\g
J 0
(-2315 460);
DISPLAY 0.659574 (-2315 460);
PAINT MONO (-2315 460);
DISPLAY INVISIBLE (-2315 460);
FORCEPROP 2 LAST CDS_LIB pure_quanta_power
J 0
(-2325 400);
DISPLAY INVISIBLE (-2325 400);
FORCEPROP 1 LAST PATH I24
J 0
(-2250 400);
DISPLAY 0.872340 (-2250 400);
PAINT AQUA (-2250 400);
DISPLAY INVISIBLE (-2250 400);
FORCEPROP 1 LAST HDL_POWER GND
J 1
(-2300 325);
DISPLAY 0.872340 (-2300 325);
PAINT GREEN (-2300 325);
DISPLAY INVISIBLE (-2300 325);
FORCEADD QUANTA_TITLE_BLOCK_C..1
(-100 100);
FORCEPROP 0 LAST CDS_CON_LAST_MODIFIED Fri Mar 11 14:52:27 2022
J 0
(-1985 115);
DISPLAY INVISIBLE (-1985 115);
FORCEPROP 1 LAST CUSTOM_TXT_CDS <CON_LAST_MODIFIED>
J 0
(-1985 115);
DISPLAY 0.978723 (-1985 115);
FORCEPROP 2 LAST CUSTOM_TXT_CDS <XR_PAGE_TITLE>
J 0
(-7990 5350);
DISPLAY 0.638298 (-7990 5350);
PAINT PINK (-7990 5350);
DISPLAY INVISIBLE (-7990 5350);
FORCEPROP 1 LAST CUSTOM_TXT_CDS <NAME_2>
J 0
(-3275 150);
FORCEPROP 1 LAST CUSTOM_TXT_CDS <NAME_1>
J 0
(-3275 275);
FORCEPROP 1 LAST CUSTOM_TXT_CDS <Q_NUMBER>
J 0
(-1503 203);
DISPLAY 1.212766 (-1503 203);
FORCEPROP 1 LAST CUSTOM_TXT_CDS <Q_PROJ>
J 0
(-2482 202);
DISPLAY 1.212766 (-2482 202);
FORCEPROP 1 LAST CUSTOM_TXT_CDS <Q_REV>
J 0
(-284 203);
DISPLAY 1.212766 (-284 203);
FORCEPROP 1 LAST CUSTOM_TXT_CDS <CON_PAGE_NUM> OF <CON_TOTAL_PAGES>
J 0
(-546 118);
DISPLAY 0.978723 (-546 118);
FORCEPROP 1 LAST Q_TITLE CPU0 VSS 2/3
J 0
(-9400 150);
DISPLAY 2.446809 (-9400 150);
PAINT GREEN (-9400 150);
FORCEPROP 1 LAST Q_DEPT BU9
J 1
(-3863 149);
DISPLAY 1.957447 (-3863 149);
PAINT GREEN (-3863 149);
FORCEPROP 2 LAST CDS_LIB pure_quanta
J 0
(-100 100);
DISPLAY INVISIBLE (-100 100);
FORCEPROP 1 LAST CDS_LMAN_SYM_OUTLINE -9475,6775,100,-125
J 0
(-100 100);
DISPLAY 0.468085 (-100 100);
PAINT GREEN (-100 100);
DISPLAY INVISIBLE (-100 100);
FORCEPROP 2 LAST PAGE_BORDER TRUE
J 0
(-7990 5350);
DISPLAY 0.638298 (-7990 5350);
PAINT PINK (-7990 5350);
DISPLAY INVISIBLE (-7990 5350);
FORCEPROP 1 LAST COMMENT_BODY TRUE
J 0
(-88 87);
DISPLAY 0.978723 (-88 87);
PAINT GREEN (-88 87);
DISPLAY INVISIBLE (-88 87);
FORCEPROP 2 LAST CDS_XR_PAGE_TITLE CR-32 : @T6G_MB_LIB.T6G(SCH_1):PAGE32
J 0
(-7990 5350);
DISPLAY 0.638298 (-7990 5350);
PAINT PINK (-7990 5350);
DISPLAY INVISIBLE (-7990 5350);
WIRE 16 -1 (-8500 550)(-8500 500);
WIRE 16 -1 (-8500 550)(-8325 550);
WIRE 16 -1 (-8500 600)(-8500 550);
WIRE 16 -1 (-8325 500)(-8500 500);
WIRE 16 -1 (-8500 500)(-8500 450);
WIRE 16 -1 (-8500 600)(-8325 600);
WIRE 16 -1 (-8500 650)(-8500 600);
WIRE 16 -1 (-8500 650)(-8325 650);
WIRE 16 -1 (-8500 700)(-8500 650);
WIRE 16 -1 (-8500 700)(-8325 700);
WIRE 16 -1 (-8500 750)(-8500 700);
WIRE 16 -1 (-8325 750)(-8500 750);
WIRE 16 -1 (-8500 800)(-8500 750);
WIRE 16 -1 (-8500 800)(-8325 800);
WIRE 16 -1 (-8500 850)(-8500 800);
WIRE 16 -1 (-8500 850)(-8325 850);
WIRE 16 -1 (-8500 900)(-8500 850);
WIRE 16 -1 (-8500 900)(-8325 900);
WIRE 16 -1 (-8500 950)(-8500 900);
WIRE 16 -1 (-8500 950)(-8325 950);
WIRE 16 -1 (-8500 1000)(-8500 950);
WIRE 16 -1 (-8500 1050)(-8500 1000);
WIRE 16 -1 (-8325 1000)(-8500 1000);
WIRE 16 -1 (-8500 1050)(-8325 1050);
WIRE 16 -1 (-8500 1100)(-8500 1050);
WIRE 16 -1 (-8500 1100)(-8325 1100);
WIRE 16 -1 (-8500 1150)(-8500 1100);
WIRE 16 -1 (-8500 1150)(-8325 1150);
WIRE 16 -1 (-8500 1200)(-8500 1150);
WIRE 16 -1 (-8500 1200)(-8325 1200);
WIRE 16 -1 (-8500 1250)(-8500 1200);
WIRE 16 -1 (-8325 1250)(-8500 1250);
WIRE 16 -1 (-8500 1300)(-8500 1250);
WIRE 16 -1 (-8500 1300)(-8325 1300);
WIRE 16 -1 (-8500 1350)(-8500 1300);
WIRE 16 -1 (-8500 1350)(-8325 1350);
WIRE 16 -1 (-8500 1400)(-8500 1350);
WIRE 16 -1 (-8500 1400)(-8325 1400);
WIRE 16 -1 (-8500 1450)(-8500 1400);
WIRE 16 -1 (-8500 1450)(-8325 1450);
WIRE 16 -1 (-8500 1500)(-8500 1450);
WIRE 16 -1 (-8500 1550)(-8500 1500);
WIRE 16 -1 (-8325 1500)(-8500 1500);
WIRE 16 -1 (-8500 1550)(-8325 1550);
WIRE 16 -1 (-8500 1600)(-8500 1550);
WIRE 16 -1 (-8500 1600)(-8325 1600);
WIRE 16 -1 (-8500 1650)(-8500 1600);
WIRE 16 -1 (-8500 1650)(-8325 1650);
WIRE 16 -1 (-8500 1700)(-8500 1650);
WIRE 16 -1 (-8500 1700)(-8325 1700);
WIRE 16 -1 (-8500 1750)(-8500 1700);
WIRE 16 -1 (-8325 1750)(-8500 1750);
WIRE 16 -1 (-8500 1800)(-8500 1750);
WIRE 16 -1 (-8500 1800)(-8325 1800);
WIRE 16 -1 (-8500 1850)(-8500 1800);
WIRE 16 -1 (-8500 1850)(-8325 1850);
WIRE 16 -1 (-8500 1900)(-8500 1850);
WIRE 16 -1 (-8500 1900)(-8325 1900);
WIRE 16 -1 (-8500 1950)(-8500 1900);
WIRE 16 -1 (-8500 1950)(-8325 1950);
WIRE 16 -1 (-8500 2000)(-8500 1950);
WIRE 16 -1 (-8500 2050)(-8500 2000);
WIRE 16 -1 (-8325 2000)(-8500 2000);
WIRE 16 -1 (-8500 2050)(-8325 2050);
WIRE 16 -1 (-8500 2100)(-8500 2050);
WIRE 16 -1 (-8500 2100)(-8325 2100);
WIRE 16 -1 (-8500 2150)(-8500 2100);
WIRE 16 -1 (-8500 2150)(-8325 2150);
WIRE 16 -1 (-8500 2200)(-8500 2150);
WIRE 16 -1 (-8500 2200)(-8325 2200);
WIRE 16 -1 (-8500 2250)(-8500 2200);
WIRE 16 -1 (-8500 2250)(-8325 2250);
WIRE 16 -1 (-8500 2300)(-8500 2250);
WIRE 16 -1 (-8325 2300)(-8500 2300);
WIRE 16 -1 (-8500 2350)(-8500 2300);
WIRE 16 -1 (-8500 2350)(-8325 2350);
WIRE 16 -1 (-8500 2400)(-8500 2350);
WIRE 16 -1 (-8500 2400)(-8325 2400);
WIRE 16 -1 (-8500 2450)(-8500 2400);
WIRE 16 -1 (-8500 2450)(-8325 2450);
WIRE 16 -1 (-8500 2500)(-8500 2450);
WIRE 16 -1 (-8500 2500)(-8325 2500);
WIRE 16 -1 (-8500 2550)(-8500 2500);
WIRE 16 -1 (-8500 2600)(-8500 2550);
WIRE 16 -1 (-8325 2550)(-8500 2550);
WIRE 16 -1 (-8500 2600)(-8325 2600);
WIRE 16 -1 (-8500 2650)(-8500 2600);
WIRE 16 -1 (-8500 2650)(-8325 2650);
WIRE 16 -1 (-8500 2700)(-8500 2650);
WIRE 16 -1 (-8500 2700)(-8325 2700);
WIRE 16 -1 (-8500 2750)(-8500 2700);
WIRE 16 -1 (-8500 2750)(-8325 2750);
WIRE 16 -1 (-8500 2800)(-8500 2750);
WIRE 16 -1 (-8325 2800)(-8500 2800);
WIRE 16 -1 (-8500 2850)(-8500 2800);
WIRE 16 -1 (-8500 2850)(-8325 2850);
WIRE 16 -1 (-8500 2900)(-8500 2850);
WIRE 16 -1 (-8500 2900)(-8325 2900);
WIRE 16 -1 (-8500 2950)(-8500 2900);
WIRE 16 -1 (-8500 2950)(-8325 2950);
WIRE 16 -1 (-8500 3000)(-8500 2950);
WIRE 16 -1 (-8500 3000)(-8325 3000);
WIRE 16 -1 (-8500 3050)(-8500 3000);
WIRE 16 -1 (-8500 3100)(-8500 3050);
WIRE 16 -1 (-8325 3050)(-8500 3050);
WIRE 16 -1 (-8500 3100)(-8325 3100);
WIRE 16 -1 (-8500 3150)(-8500 3100);
WIRE 16 -1 (-8500 3150)(-8325 3150);
WIRE 16 -1 (-8500 3200)(-8500 3150);
WIRE 16 -1 (-8500 3200)(-8325 3200);
WIRE 16 -1 (-8500 3250)(-8500 3200);
WIRE 16 -1 (-8500 3250)(-8325 3250);
WIRE 16 -1 (-8500 3300)(-8500 3250);
WIRE 16 -1 (-8325 3300)(-8500 3300);
WIRE 16 -1 (-8500 3350)(-8500 3300);
WIRE 16 -1 (-8500 3350)(-8325 3350);
WIRE 16 -1 (-8500 3400)(-8500 3350);
WIRE 16 -1 (-8500 3400)(-8325 3400);
WIRE 16 -1 (-8500 3450)(-8500 3400);
WIRE 16 -1 (-8500 3450)(-8325 3450);
WIRE 16 -1 (-8500 3500)(-8500 3450);
WIRE 16 -1 (-8500 3500)(-8325 3500);
WIRE 16 -1 (-8500 3550)(-8500 3500);
WIRE 16 -1 (-8500 3600)(-8500 3550);
WIRE 16 -1 (-8325 3550)(-8500 3550);
WIRE 16 -1 (-8500 3600)(-8325 3600);
WIRE 16 -1 (-8500 3650)(-8500 3600);
WIRE 16 -1 (-8500 3650)(-8325 3650);
WIRE 16 -1 (-8500 3700)(-8500 3650);
WIRE 16 -1 (-8500 3700)(-8325 3700);
WIRE 16 -1 (-8500 3750)(-8500 3700);
WIRE 16 -1 (-8500 3750)(-8325 3750);
WIRE 16 -1 (-8500 3800)(-8500 3750);
WIRE 16 -1 (-8325 3800)(-8500 3800);
WIRE 16 -1 (-8500 3850)(-8500 3800);
WIRE 16 -1 (-8500 3850)(-8325 3850);
WIRE 16 -1 (-8500 3900)(-8500 3850);
WIRE 16 -1 (-8500 3900)(-8325 3900);
WIRE 16 -1 (-8500 3950)(-8500 3900);
WIRE 16 -1 (-8500 3950)(-8325 3950);
WIRE 16 -1 (-8500 4000)(-8500 3950);
WIRE 16 -1 (-8500 4000)(-8325 4000);
WIRE 16 -1 (-8500 4050)(-8500 4000);
WIRE 16 -1 (-8500 4100)(-8500 4050);
WIRE 16 -1 (-8325 4050)(-8500 4050);
WIRE 16 -1 (-8500 4100)(-8325 4100);
WIRE 16 -1 (-8500 4150)(-8500 4100);
WIRE 16 -1 (-8500 4150)(-8325 4150);
WIRE 16 -1 (-8500 4200)(-8500 4150);
WIRE 16 -1 (-8500 4200)(-8325 4200);
WIRE 16 -1 (-8500 4250)(-8500 4200);
WIRE 16 -1 (-8500 4250)(-8325 4250);
WIRE 16 -1 (-8500 4300)(-8500 4250);
WIRE 16 -1 (-8500 4300)(-8325 4300);
WIRE 16 -1 (-8500 4350)(-8500 4300);
WIRE 16 -1 (-8325 4350)(-8500 4350);
WIRE 16 -1 (-8500 4400)(-8500 4350);
WIRE 16 -1 (-8500 4400)(-8325 4400);
WIRE 16 -1 (-8500 4450)(-8500 4400);
WIRE 16 -1 (-8500 4450)(-8325 4450);
WIRE 16 -1 (-8500 4500)(-8500 4450);
WIRE 16 -1 (-8500 4500)(-8325 4500);
WIRE 16 -1 (-8500 4550)(-8500 4500);
WIRE 16 -1 (-8500 4550)(-8325 4550);
WIRE 16 -1 (-8500 4600)(-8500 4550);
WIRE 16 -1 (-8500 4650)(-8500 4600);
WIRE 16 -1 (-8325 4600)(-8500 4600);
WIRE 16 -1 (-8500 4650)(-8325 4650);
WIRE 16 -1 (-8500 4700)(-8500 4650);
WIRE 16 -1 (-8500 4700)(-8325 4700);
WIRE 16 -1 (-8500 4750)(-8500 4700);
WIRE 16 -1 (-8500 4750)(-8325 4750);
WIRE 16 -1 (-8500 4800)(-8500 4750);
WIRE 16 -1 (-8500 4800)(-8325 4800);
WIRE 16 -1 (-8500 4850)(-8500 4800);
WIRE 16 -1 (-8325 4850)(-8500 4850);
WIRE 16 -1 (-8500 4900)(-8500 4850);
WIRE 16 -1 (-8500 4900)(-8325 4900);
WIRE 16 -1 (-8500 4950)(-8500 4900);
WIRE 16 -1 (-8500 4950)(-8325 4950);
WIRE 16 -1 (-8500 5000)(-8500 4950);
WIRE 16 -1 (-8500 5000)(-8325 5000);
WIRE 16 -1 (-8500 5050)(-8500 5000);
WIRE 16 -1 (-8500 5050)(-8325 5050);
WIRE 16 -1 (-8500 5100)(-8500 5050);
WIRE 16 -1 (-8500 5150)(-8500 5100);
WIRE 16 -1 (-8325 5100)(-8500 5100);
WIRE 16 -1 (-8500 5150)(-8325 5150);
WIRE 16 -1 (-8500 5200)(-8500 5150);
WIRE 16 -1 (-8500 5200)(-8325 5200);
WIRE 16 -1 (-8500 5250)(-8500 5200);
WIRE 16 -1 (-8500 5250)(-8325 5250);
WIRE 16 -1 (-8500 5300)(-8500 5250);
WIRE 16 -1 (-8500 5300)(-8325 5300);
WIRE 16 -1 (-8500 5350)(-8500 5300);
WIRE 16 -1 (-8325 5350)(-8500 5350);
WIRE 16 -1 (-8500 5400)(-8500 5350);
WIRE 16 -1 (-8500 5400)(-8325 5400);
WIRE 16 -1 (-8500 5450)(-8500 5400);
WIRE 16 -1 (-8500 5450)(-8325 5450);
WIRE 16 -1 (-8500 5500)(-8500 5450);
WIRE 16 -1 (-8500 5500)(-8325 5500);
WIRE 16 -1 (-8500 5550)(-8500 5500);
WIRE 16 -1 (-8500 5550)(-8325 5550);
WIRE 16 -1 (-8500 5600)(-8500 5550);
WIRE 16 -1 (-8500 5650)(-8500 5600);
WIRE 16 -1 (-8325 5600)(-8500 5600);
WIRE 16 -1 (-8500 5650)(-8325 5650);
WIRE 16 -1 (-8500 5700)(-8500 5650);
WIRE 16 -1 (-8500 5700)(-8325 5700);
WIRE 16 -1 (-8500 5750)(-8500 5700);
WIRE 16 -1 (-8500 5750)(-8325 5750);
WIRE 16 -1 (-8500 5800)(-8500 5750);
WIRE 16 -1 (-8500 5800)(-8325 5800);
WIRE 16 -1 (-8500 5850)(-8500 5800);
WIRE 16 -1 (-8325 5850)(-8500 5850);
WIRE 16 -1 (-8500 5900)(-8500 5850);
WIRE 16 -1 (-8500 5900)(-8325 5900);
WIRE 16 -1 (-8500 5950)(-8500 5900);
WIRE 16 -1 (-8500 5950)(-8325 5950);
WIRE 16 -1 (-8500 6000)(-8500 5950);
WIRE 16 -1 (-8500 6000)(-8325 6000);
WIRE 16 -1 (-8500 6050)(-8500 6000);
WIRE 16 -1 (-8500 6050)(-8325 6050);
WIRE 16 -1 (-8500 6100)(-8500 6050);
WIRE 16 -1 (-8500 6150)(-8500 6100);
WIRE 16 -1 (-8325 6100)(-8500 6100);
WIRE 16 -1 (-8500 6150)(-8325 6150);
WIRE 16 -1 (-8500 6200)(-8500 6150);
WIRE 16 -1 (-8500 6200)(-8325 6200);
WIRE 16 -1 (-8500 6250)(-8500 6200);
WIRE 16 -1 (-8500 6250)(-8325 6250);
WIRE 16 -1 (-8500 6300)(-8500 6250);
WIRE 16 -1 (-8500 6300)(-8325 6300);
WIRE 16 -1 (-8500 6350)(-8500 6300);
WIRE 16 -1 (-8325 6350)(-8500 6350);
WIRE 16 -1 (-8500 6400)(-8500 6350);
WIRE 16 -1 (-8500 6400)(-8325 6400);
WIRE 16 -1 (-7225 550)(-7050 550);
WIRE 16 -1 (-7050 600)(-7050 550);
WIRE 16 -1 (-7050 475)(-7050 550);
WIRE 16 -1 (-7225 600)(-7050 600);
WIRE 16 -1 (-7050 650)(-7050 600);
WIRE 16 -1 (-7225 650)(-7050 650);
WIRE 16 -1 (-7050 700)(-7050 650);
WIRE 16 -1 (-7225 700)(-7050 700);
WIRE 16 -1 (-7050 750)(-7050 700);
WIRE 16 -1 (-7225 750)(-7050 750);
WIRE 16 -1 (-7050 800)(-7050 750);
WIRE 16 -1 (-7225 800)(-7050 800);
WIRE 16 -1 (-7050 850)(-7050 800);
WIRE 16 -1 (-7225 850)(-7050 850);
WIRE 16 -1 (-7050 900)(-7050 850);
WIRE 16 -1 (-7225 900)(-7050 900);
WIRE 16 -1 (-7050 950)(-7050 900);
WIRE 16 -1 (-7225 950)(-7050 950);
WIRE 16 -1 (-7050 1000)(-7050 950);
WIRE 16 -1 (-7225 1000)(-7050 1000);
WIRE 16 -1 (-7050 1050)(-7050 1000);
WIRE 16 -1 (-7225 1050)(-7050 1050);
WIRE 16 -1 (-7050 1100)(-7050 1050);
WIRE 16 -1 (-7225 1100)(-7050 1100);
WIRE 16 -1 (-7050 1150)(-7050 1100);
WIRE 16 -1 (-7225 1150)(-7050 1150);
WIRE 16 -1 (-7050 1200)(-7050 1150);
WIRE 16 -1 (-7225 1200)(-7050 1200);
WIRE 16 -1 (-7050 1250)(-7050 1200);
WIRE 16 -1 (-7225 1250)(-7050 1250);
WIRE 16 -1 (-7050 1300)(-7050 1250);
WIRE 16 -1 (-7225 1300)(-7050 1300);
WIRE 16 -1 (-7050 1350)(-7050 1300);
WIRE 16 -1 (-7225 1350)(-7050 1350);
WIRE 16 -1 (-7050 1400)(-7050 1350);
WIRE 16 -1 (-7225 1400)(-7050 1400);
WIRE 16 -1 (-7050 1450)(-7050 1400);
WIRE 16 -1 (-7225 1450)(-7050 1450);
WIRE 16 -1 (-7050 1500)(-7050 1450);
WIRE 16 -1 (-7225 1500)(-7050 1500);
WIRE 16 -1 (-7050 1550)(-7050 1500);
WIRE 16 -1 (-7225 1550)(-7050 1550);
WIRE 16 -1 (-7050 1600)(-7050 1550);
WIRE 16 -1 (-7225 1600)(-7050 1600);
WIRE 16 -1 (-7050 1650)(-7050 1600);
WIRE 16 -1 (-7225 1650)(-7050 1650);
WIRE 16 -1 (-7050 1700)(-7050 1650);
WIRE 16 -1 (-7225 1700)(-7050 1700);
WIRE 16 -1 (-7050 1750)(-7050 1700);
WIRE 16 -1 (-7225 1750)(-7050 1750);
WIRE 16 -1 (-7050 1800)(-7050 1750);
WIRE 16 -1 (-7225 1800)(-7050 1800);
WIRE 16 -1 (-7050 1850)(-7050 1800);
WIRE 16 -1 (-7225 1850)(-7050 1850);
WIRE 16 -1 (-7050 1900)(-7050 1850);
WIRE 16 -1 (-7225 1900)(-7050 1900);
WIRE 16 -1 (-7050 1950)(-7050 1900);
WIRE 16 -1 (-7225 1950)(-7050 1950);
WIRE 16 -1 (-7050 2000)(-7050 1950);
WIRE 16 -1 (-7225 2000)(-7050 2000);
WIRE 16 -1 (-7050 2050)(-7050 2000);
WIRE 16 -1 (-7050 2100)(-7050 2050);
WIRE 16 -1 (-7225 2050)(-7050 2050);
WIRE 16 -1 (-7225 2100)(-7050 2100);
WIRE 16 -1 (-7050 2150)(-7050 2100);
WIRE 16 -1 (-7225 2150)(-7050 2150);
WIRE 16 -1 (-7050 2200)(-7050 2150);
WIRE 16 -1 (-7225 2200)(-7050 2200);
WIRE 16 -1 (-7050 2250)(-7050 2200);
WIRE 16 -1 (-7225 2250)(-7050 2250);
WIRE 16 -1 (-7050 2300)(-7050 2250);
WIRE 16 -1 (-7225 2300)(-7050 2300);
WIRE 16 -1 (-7050 2350)(-7050 2300);
WIRE 16 -1 (-7225 2350)(-7050 2350);
WIRE 16 -1 (-7050 2400)(-7050 2350);
WIRE 16 -1 (-7225 2400)(-7050 2400);
WIRE 16 -1 (-7050 2450)(-7050 2400);
WIRE 16 -1 (-7225 2450)(-7050 2450);
WIRE 16 -1 (-7050 2500)(-7050 2450);
WIRE 16 -1 (-7225 2500)(-7050 2500);
WIRE 16 -1 (-7050 2550)(-7050 2500);
WIRE 16 -1 (-7225 2550)(-7050 2550);
WIRE 16 -1 (-7050 2600)(-7050 2550);
WIRE 16 -1 (-7225 2600)(-7050 2600);
WIRE 16 -1 (-7050 2650)(-7050 2600);
WIRE 16 -1 (-7225 2650)(-7050 2650);
WIRE 16 -1 (-7050 2700)(-7050 2650);
WIRE 16 -1 (-7225 2700)(-7050 2700);
WIRE 16 -1 (-7050 2750)(-7050 2700);
WIRE 16 -1 (-7225 2750)(-7050 2750);
WIRE 16 -1 (-7050 2800)(-7050 2750);
WIRE 16 -1 (-7225 2800)(-7050 2800);
WIRE 16 -1 (-7050 2850)(-7050 2800);
WIRE 16 -1 (-7225 2850)(-7050 2850);
WIRE 16 -1 (-7050 2900)(-7050 2850);
WIRE 16 -1 (-7225 2900)(-7050 2900);
WIRE 16 -1 (-7050 2950)(-7050 2900);
WIRE 16 -1 (-7225 2950)(-7050 2950);
WIRE 16 -1 (-7050 3000)(-7050 2950);
WIRE 16 -1 (-7225 3000)(-7050 3000);
WIRE 16 -1 (-7050 3050)(-7050 3000);
WIRE 16 -1 (-7225 3050)(-7050 3050);
WIRE 16 -1 (-7050 3100)(-7050 3050);
WIRE 16 -1 (-7225 3100)(-7050 3100);
WIRE 16 -1 (-7050 3150)(-7050 3100);
WIRE 16 -1 (-7225 3150)(-7050 3150);
WIRE 16 -1 (-7050 3200)(-7050 3150);
WIRE 16 -1 (-7225 3200)(-7050 3200);
WIRE 16 -1 (-7050 3250)(-7050 3200);
WIRE 16 -1 (-7225 3250)(-7050 3250);
WIRE 16 -1 (-7050 3300)(-7050 3250);
WIRE 16 -1 (-7225 3300)(-7050 3300);
WIRE 16 -1 (-7050 3350)(-7050 3300);
WIRE 16 -1 (-7225 3350)(-7050 3350);
WIRE 16 -1 (-7050 3400)(-7050 3350);
WIRE 16 -1 (-7225 3400)(-7050 3400);
WIRE 16 -1 (-7050 3450)(-7050 3400);
WIRE 16 -1 (-7225 3450)(-7050 3450);
WIRE 16 -1 (-7050 3500)(-7050 3450);
WIRE 16 -1 (-7225 3500)(-7050 3500);
WIRE 16 -1 (-7050 3550)(-7050 3500);
WIRE 16 -1 (-7225 3550)(-7050 3550);
WIRE 16 -1 (-7050 3600)(-7050 3550);
WIRE 16 -1 (-7225 3600)(-7050 3600);
WIRE 16 -1 (-7050 3650)(-7050 3600);
WIRE 16 -1 (-7225 3650)(-7050 3650);
WIRE 16 -1 (-7050 3700)(-7050 3650);
WIRE 16 -1 (-7225 3700)(-7050 3700);
WIRE 16 -1 (-7050 3750)(-7050 3700);
WIRE 16 -1 (-7225 3750)(-7050 3750);
WIRE 16 -1 (-7050 3800)(-7050 3750);
WIRE 16 -1 (-7225 3800)(-7050 3800);
WIRE 16 -1 (-7050 3850)(-7050 3800);
WIRE 16 -1 (-7225 3850)(-7050 3850);
WIRE 16 -1 (-7050 3900)(-7050 3850);
WIRE 16 -1 (-7225 3900)(-7050 3900);
WIRE 16 -1 (-7050 3950)(-7050 3900);
WIRE 16 -1 (-7225 3950)(-7050 3950);
WIRE 16 -1 (-7050 4000)(-7050 3950);
WIRE 16 -1 (-7225 4000)(-7050 4000);
WIRE 16 -1 (-7050 4050)(-7050 4000);
WIRE 16 -1 (-7225 4050)(-7050 4050);
WIRE 16 -1 (-7050 4100)(-7050 4050);
WIRE 16 -1 (-7050 4150)(-7050 4100);
WIRE 16 -1 (-7225 4100)(-7050 4100);
WIRE 16 -1 (-7225 4150)(-7050 4150);
WIRE 16 -1 (-7050 4200)(-7050 4150);
WIRE 16 -1 (-7225 4200)(-7050 4200);
WIRE 16 -1 (-7050 4250)(-7050 4200);
WIRE 16 -1 (-7225 4250)(-7050 4250);
WIRE 16 -1 (-7050 4300)(-7050 4250);
WIRE 16 -1 (-7225 4300)(-7050 4300);
WIRE 16 -1 (-7050 4350)(-7050 4300);
WIRE 16 -1 (-7225 4350)(-7050 4350);
WIRE 16 -1 (-7050 4400)(-7050 4350);
WIRE 16 -1 (-7225 4400)(-7050 4400);
WIRE 16 -1 (-7050 4450)(-7050 4400);
WIRE 16 -1 (-7225 4450)(-7050 4450);
WIRE 16 -1 (-7050 4500)(-7050 4450);
WIRE 16 -1 (-7225 4500)(-7050 4500);
WIRE 16 -1 (-7050 4550)(-7050 4500);
WIRE 16 -1 (-7225 4550)(-7050 4550);
WIRE 16 -1 (-7050 4600)(-7050 4550);
WIRE 16 -1 (-7225 4600)(-7050 4600);
WIRE 16 -1 (-7050 4650)(-7050 4600);
WIRE 16 -1 (-7225 4650)(-7050 4650);
WIRE 16 -1 (-7050 4700)(-7050 4650);
WIRE 16 -1 (-7225 4700)(-7050 4700);
WIRE 16 -1 (-7050 4750)(-7050 4700);
WIRE 16 -1 (-7225 4750)(-7050 4750);
WIRE 16 -1 (-7050 4800)(-7050 4750);
WIRE 16 -1 (-7225 4800)(-7050 4800);
WIRE 16 -1 (-7050 4850)(-7050 4800);
WIRE 16 -1 (-7225 4850)(-7050 4850);
WIRE 16 -1 (-7050 4900)(-7050 4850);
WIRE 16 -1 (-7225 4900)(-7050 4900);
WIRE 16 -1 (-7050 4950)(-7050 4900);
WIRE 16 -1 (-7225 4950)(-7050 4950);
WIRE 16 -1 (-7050 5000)(-7050 4950);
WIRE 16 -1 (-7225 5000)(-7050 5000);
WIRE 16 -1 (-7050 5050)(-7050 5000);
WIRE 16 -1 (-7225 5050)(-7050 5050);
WIRE 16 -1 (-7050 5100)(-7050 5050);
WIRE 16 -1 (-7225 5100)(-7050 5100);
WIRE 16 -1 (-7050 5150)(-7050 5100);
WIRE 16 -1 (-7225 5150)(-7050 5150);
WIRE 16 -1 (-7050 5200)(-7050 5150);
WIRE 16 -1 (-7225 5200)(-7050 5200);
WIRE 16 -1 (-7050 5250)(-7050 5200);
WIRE 16 -1 (-7225 5250)(-7050 5250);
WIRE 16 -1 (-7050 5300)(-7050 5250);
WIRE 16 -1 (-7225 5300)(-7050 5300);
WIRE 16 -1 (-7050 5350)(-7050 5300);
WIRE 16 -1 (-7225 5350)(-7050 5350);
WIRE 16 -1 (-7050 5400)(-7050 5350);
WIRE 16 -1 (-7225 5400)(-7050 5400);
WIRE 16 -1 (-7050 5450)(-7050 5400);
WIRE 16 -1 (-7225 5450)(-7050 5450);
WIRE 16 -1 (-7050 5500)(-7050 5450);
WIRE 16 -1 (-7225 5500)(-7050 5500);
WIRE 16 -1 (-7050 5550)(-7050 5500);
WIRE 16 -1 (-7225 5550)(-7050 5550);
WIRE 16 -1 (-7050 5600)(-7050 5550);
WIRE 16 -1 (-7225 5600)(-7050 5600);
WIRE 16 -1 (-7050 5650)(-7050 5600);
WIRE 16 -1 (-7225 5650)(-7050 5650);
WIRE 16 -1 (-7050 5700)(-7050 5650);
WIRE 16 -1 (-7225 5700)(-7050 5700);
WIRE 16 -1 (-7050 5750)(-7050 5700);
WIRE 16 -1 (-7225 5750)(-7050 5750);
WIRE 16 -1 (-7050 5800)(-7050 5750);
WIRE 16 -1 (-7225 5800)(-7050 5800);
WIRE 16 -1 (-7050 5850)(-7050 5800);
WIRE 16 -1 (-7225 5850)(-7050 5850);
WIRE 16 -1 (-7050 5900)(-7050 5850);
WIRE 16 -1 (-7225 5900)(-7050 5900);
WIRE 16 -1 (-7050 5950)(-7050 5900);
WIRE 16 -1 (-7225 5950)(-7050 5950);
WIRE 16 -1 (-7050 6000)(-7050 5950);
WIRE 16 -1 (-7225 6000)(-7050 6000);
WIRE 16 -1 (-7050 6050)(-7050 6000);
WIRE 16 -1 (-7225 6050)(-7050 6050);
WIRE 16 -1 (-7050 6100)(-7050 6050);
WIRE 16 -1 (-7225 6100)(-7050 6100);
WIRE 16 -1 (-7050 6150)(-7050 6100);
WIRE 16 -1 (-7050 6200)(-7050 6150);
WIRE 16 -1 (-7225 6150)(-7050 6150);
WIRE 16 -1 (-7225 6200)(-7050 6200);
WIRE 16 -1 (-7050 6250)(-7050 6200);
WIRE 16 -1 (-7225 6250)(-7050 6250);
WIRE 16 -1 (-7050 6300)(-7050 6250);
WIRE 16 -1 (-7225 6300)(-7050 6300);
WIRE 16 -1 (-7050 6350)(-7050 6300);
WIRE 16 -1 (-7225 6350)(-7050 6350);
WIRE 16 -1 (-7050 6400)(-7050 6350);
WIRE 16 -1 (-7225 6400)(-7050 6400);
WIRE 16 -1 (-6475 475)(-6475 500);
WIRE 16 -1 (-6475 550)(-6475 500);
WIRE 16 -1 (-6475 500)(-6300 500);
WIRE 16 -1 (-6475 550)(-6300 550);
WIRE 16 -1 (-6475 600)(-6475 550);
WIRE 16 -1 (-6475 600)(-6300 600);
WIRE 16 -1 (-6475 650)(-6475 600);
WIRE 16 -1 (-6475 650)(-6300 650);
WIRE 16 -1 (-6475 700)(-6475 650);
WIRE 16 -1 (-6300 700)(-6475 700);
WIRE 16 -1 (-6475 750)(-6475 700);
WIRE 16 -1 (-6475 750)(-6300 750);
WIRE 16 -1 (-6475 800)(-6475 750);
WIRE 16 -1 (-6475 800)(-6300 800);
WIRE 16 -1 (-6475 850)(-6475 800);
WIRE 16 -1 (-6475 850)(-6300 850);
WIRE 16 -1 (-6475 900)(-6475 850);
WIRE 16 -1 (-6475 900)(-6300 900);
WIRE 16 -1 (-6475 950)(-6475 900);
WIRE 16 -1 (-6300 950)(-6475 950);
WIRE 16 -1 (-6475 1000)(-6475 950);
WIRE 16 -1 (-6475 1050)(-6475 1000);
WIRE 16 -1 (-6475 1000)(-6300 1000);
WIRE 16 -1 (-6475 1050)(-6300 1050);
WIRE 16 -1 (-6475 1100)(-6475 1050);
WIRE 16 -1 (-6475 1100)(-6300 1100);
WIRE 16 -1 (-6475 1150)(-6475 1100);
WIRE 16 -1 (-6475 1150)(-6300 1150);
WIRE 16 -1 (-6475 1200)(-6475 1150);
WIRE 16 -1 (-6300 1200)(-6475 1200);
WIRE 16 -1 (-6475 1250)(-6475 1200);
WIRE 16 -1 (-6475 1250)(-6300 1250);
WIRE 16 -1 (-6475 1300)(-6475 1250);
WIRE 16 -1 (-6475 1300)(-6300 1300);
WIRE 16 -1 (-6475 1350)(-6475 1300);
WIRE 16 -1 (-6475 1350)(-6300 1350);
WIRE 16 -1 (-6475 1400)(-6475 1350);
WIRE 16 -1 (-6475 1400)(-6300 1400);
WIRE 16 -1 (-6475 1450)(-6475 1400);
WIRE 16 -1 (-6300 1450)(-6475 1450);
WIRE 16 -1 (-6475 1500)(-6475 1450);
WIRE 16 -1 (-6475 1550)(-6475 1500);
WIRE 16 -1 (-6475 1500)(-6300 1500);
WIRE 16 -1 (-6475 1550)(-6300 1550);
WIRE 16 -1 (-6475 1600)(-6475 1550);
WIRE 16 -1 (-6475 1600)(-6300 1600);
WIRE 16 -1 (-6475 1650)(-6475 1600);
WIRE 16 -1 (-6475 1650)(-6300 1650);
WIRE 16 -1 (-6475 1700)(-6475 1650);
WIRE 16 -1 (-6300 1700)(-6475 1700);
WIRE 16 -1 (-6475 1750)(-6475 1700);
WIRE 16 -1 (-6475 1750)(-6300 1750);
WIRE 16 -1 (-6475 1800)(-6475 1750);
WIRE 16 -1 (-6475 1800)(-6300 1800);
WIRE 16 -1 (-6475 1850)(-6475 1800);
WIRE 16 -1 (-6475 1850)(-6300 1850);
WIRE 16 -1 (-6475 1900)(-6475 1850);
WIRE 16 -1 (-6475 1900)(-6300 1900);
WIRE 16 -1 (-6475 1950)(-6475 1900);
WIRE 16 -1 (-6300 1950)(-6475 1950);
WIRE 16 -1 (-6475 2000)(-6475 1950);
WIRE 16 -1 (-6475 2050)(-6475 2000);
WIRE 16 -1 (-6475 2000)(-6300 2000);
WIRE 16 -1 (-6475 2050)(-6300 2050);
WIRE 16 -1 (-6475 2100)(-6475 2050);
WIRE 16 -1 (-6475 2100)(-6300 2100);
WIRE 16 -1 (-6475 2150)(-6475 2100);
WIRE 16 -1 (-6475 2150)(-6300 2150);
WIRE 16 -1 (-6475 2200)(-6475 2150);
WIRE 16 -1 (-6475 2200)(-6300 2200);
WIRE 16 -1 (-6475 2250)(-6475 2200);
WIRE 16 -1 (-6300 2250)(-6475 2250);
WIRE 16 -1 (-6475 2300)(-6475 2250);
WIRE 16 -1 (-6475 2300)(-6300 2300);
WIRE 16 -1 (-6475 2350)(-6475 2300);
WIRE 16 -1 (-6475 2350)(-6300 2350);
WIRE 16 -1 (-6475 2400)(-6475 2350);
WIRE 16 -1 (-6475 2400)(-6300 2400);
WIRE 16 -1 (-6475 2450)(-6475 2400);
WIRE 16 -1 (-6475 2450)(-6300 2450);
WIRE 16 -1 (-6475 2500)(-6475 2450);
WIRE 16 -1 (-6300 2500)(-6475 2500);
WIRE 16 -1 (-6475 2550)(-6475 2500);
WIRE 16 -1 (-6475 2600)(-6475 2550);
WIRE 16 -1 (-6475 2550)(-6300 2550);
WIRE 16 -1 (-6475 2600)(-6300 2600);
WIRE 16 -1 (-6475 2650)(-6475 2600);
WIRE 16 -1 (-6475 2650)(-6300 2650);
WIRE 16 -1 (-6475 2700)(-6475 2650);
WIRE 16 -1 (-6475 2700)(-6300 2700);
WIRE 16 -1 (-6475 2750)(-6475 2700);
WIRE 16 -1 (-6300 2750)(-6475 2750);
WIRE 16 -1 (-6475 2800)(-6475 2750);
WIRE 16 -1 (-6475 2800)(-6300 2800);
WIRE 16 -1 (-6475 2850)(-6475 2800);
WIRE 16 -1 (-6475 2850)(-6300 2850);
WIRE 16 -1 (-6475 2900)(-6475 2850);
WIRE 16 -1 (-6475 2900)(-6300 2900);
WIRE 16 -1 (-6475 2950)(-6475 2900);
WIRE 16 -1 (-6475 2950)(-6300 2950);
WIRE 16 -1 (-6475 3000)(-6475 2950);
WIRE 16 -1 (-6300 3000)(-6475 3000);
WIRE 16 -1 (-6475 3050)(-6475 3000);
WIRE 16 -1 (-6475 3100)(-6475 3050);
WIRE 16 -1 (-6475 3050)(-6300 3050);
WIRE 16 -1 (-6475 3100)(-6300 3100);
WIRE 16 -1 (-6475 3150)(-6475 3100);
WIRE 16 -1 (-6475 3150)(-6300 3150);
WIRE 16 -1 (-6475 3200)(-6475 3150);
WIRE 16 -1 (-6475 3200)(-6300 3200);
WIRE 16 -1 (-6475 3250)(-6475 3200);
WIRE 16 -1 (-6300 3250)(-6475 3250);
WIRE 16 -1 (-6475 3300)(-6475 3250);
WIRE 16 -1 (-6475 3300)(-6300 3300);
WIRE 16 -1 (-6475 3350)(-6475 3300);
WIRE 16 -1 (-6475 3350)(-6300 3350);
WIRE 16 -1 (-6475 3400)(-6475 3350);
WIRE 16 -1 (-6475 3400)(-6300 3400);
WIRE 16 -1 (-6475 3450)(-6475 3400);
WIRE 16 -1 (-6475 3450)(-6300 3450);
WIRE 16 -1 (-6475 3500)(-6475 3450);
WIRE 16 -1 (-6300 3500)(-6475 3500);
WIRE 16 -1 (-6475 3550)(-6475 3500);
WIRE 16 -1 (-6475 3600)(-6475 3550);
WIRE 16 -1 (-6475 3550)(-6300 3550);
WIRE 16 -1 (-6475 3600)(-6300 3600);
WIRE 16 -1 (-6475 3650)(-6475 3600);
WIRE 16 -1 (-6475 3650)(-6300 3650);
WIRE 16 -1 (-6475 3700)(-6475 3650);
WIRE 16 -1 (-6475 3700)(-6300 3700);
WIRE 16 -1 (-6475 3750)(-6475 3700);
WIRE 16 -1 (-6300 3750)(-6475 3750);
WIRE 16 -1 (-6475 3800)(-6475 3750);
WIRE 16 -1 (-6475 3800)(-6300 3800);
WIRE 16 -1 (-6475 3850)(-6475 3800);
WIRE 16 -1 (-6475 3850)(-6300 3850);
WIRE 16 -1 (-6475 3900)(-6475 3850);
WIRE 16 -1 (-6475 3900)(-6300 3900);
WIRE 16 -1 (-6475 3950)(-6475 3900);
WIRE 16 -1 (-6475 3950)(-6300 3950);
WIRE 16 -1 (-6475 4000)(-6475 3950);
WIRE 16 -1 (-6300 4000)(-6475 4000);
WIRE 16 -1 (-6475 4050)(-6475 4000);
WIRE 16 -1 (-6475 4100)(-6475 4050);
WIRE 16 -1 (-6475 4050)(-6300 4050);
WIRE 16 -1 (-6475 4100)(-6300 4100);
WIRE 16 -1 (-6475 4150)(-6475 4100);
WIRE 16 -1 (-6475 4150)(-6300 4150);
WIRE 16 -1 (-6475 4200)(-6475 4150);
WIRE 16 -1 (-6475 4200)(-6300 4200);
WIRE 16 -1 (-6475 4250)(-6475 4200);
WIRE 16 -1 (-6475 4250)(-6300 4250);
WIRE 16 -1 (-6475 4300)(-6475 4250);
WIRE 16 -1 (-6300 4300)(-6475 4300);
WIRE 16 -1 (-6475 4350)(-6475 4300);
WIRE 16 -1 (-6475 4350)(-6300 4350);
WIRE 16 -1 (-6475 4400)(-6475 4350);
WIRE 16 -1 (-6475 4400)(-6300 4400);
WIRE 16 -1 (-6475 4450)(-6475 4400);
WIRE 16 -1 (-6475 4450)(-6300 4450);
WIRE 16 -1 (-6475 4500)(-6475 4450);
WIRE 16 -1 (-6475 4500)(-6300 4500);
WIRE 16 -1 (-6475 4550)(-6475 4500);
WIRE 16 -1 (-6300 4550)(-6475 4550);
WIRE 16 -1 (-6475 4600)(-6475 4550);
WIRE 16 -1 (-6475 4650)(-6475 4600);
WIRE 16 -1 (-6475 4600)(-6300 4600);
WIRE 16 -1 (-6475 4650)(-6300 4650);
WIRE 16 -1 (-6475 4700)(-6475 4650);
WIRE 16 -1 (-6475 4700)(-6300 4700);
WIRE 16 -1 (-6475 4750)(-6475 4700);
WIRE 16 -1 (-6475 4750)(-6300 4750);
WIRE 16 -1 (-6475 4800)(-6475 4750);
WIRE 16 -1 (-6300 4800)(-6475 4800);
WIRE 16 -1 (-6475 4850)(-6475 4800);
WIRE 16 -1 (-6475 4850)(-6300 4850);
WIRE 16 -1 (-6475 4900)(-6475 4850);
WIRE 16 -1 (-6475 4900)(-6300 4900);
WIRE 16 -1 (-6475 4950)(-6475 4900);
WIRE 16 -1 (-6475 4950)(-6300 4950);
WIRE 16 -1 (-6475 5000)(-6475 4950);
WIRE 16 -1 (-6475 5000)(-6300 5000);
WIRE 16 -1 (-6475 5050)(-6475 5000);
WIRE 16 -1 (-6300 5050)(-6475 5050);
WIRE 16 -1 (-6475 5100)(-6475 5050);
WIRE 16 -1 (-6475 5150)(-6475 5100);
WIRE 16 -1 (-6475 5100)(-6300 5100);
WIRE 16 -1 (-6475 5150)(-6300 5150);
WIRE 16 -1 (-6475 5200)(-6475 5150);
WIRE 16 -1 (-6475 5200)(-6300 5200);
WIRE 16 -1 (-6475 5250)(-6475 5200);
WIRE 16 -1 (-6475 5250)(-6300 5250);
WIRE 16 -1 (-6475 5300)(-6475 5250);
WIRE 16 -1 (-6300 5300)(-6475 5300);
WIRE 16 -1 (-6475 5350)(-6475 5300);
WIRE 16 -1 (-6475 5350)(-6300 5350);
WIRE 16 -1 (-6475 5400)(-6475 5350);
WIRE 16 -1 (-6475 5400)(-6300 5400);
WIRE 16 -1 (-6475 5450)(-6475 5400);
WIRE 16 -1 (-6475 5450)(-6300 5450);
WIRE 16 -1 (-6475 5500)(-6475 5450);
WIRE 16 -1 (-6475 5500)(-6300 5500);
WIRE 16 -1 (-6475 5550)(-6475 5500);
WIRE 16 -1 (-6300 5550)(-6475 5550);
WIRE 16 -1 (-6475 5600)(-6475 5550);
WIRE 16 -1 (-6475 5650)(-6475 5600);
WIRE 16 -1 (-6475 5600)(-6300 5600);
WIRE 16 -1 (-6475 5650)(-6300 5650);
WIRE 16 -1 (-6475 5700)(-6475 5650);
WIRE 16 -1 (-6475 5700)(-6300 5700);
WIRE 16 -1 (-6475 5750)(-6475 5700);
WIRE 16 -1 (-6475 5750)(-6300 5750);
WIRE 16 -1 (-6475 5800)(-6475 5750);
WIRE 16 -1 (-6300 5800)(-6475 5800);
WIRE 16 -1 (-6475 5850)(-6475 5800);
WIRE 16 -1 (-6475 5850)(-6300 5850);
WIRE 16 -1 (-6475 5900)(-6475 5850);
WIRE 16 -1 (-6475 5900)(-6300 5900);
WIRE 16 -1 (-6475 5950)(-6475 5900);
WIRE 16 -1 (-6475 5950)(-6300 5950);
WIRE 16 -1 (-6475 6000)(-6475 5950);
WIRE 16 -1 (-6475 6000)(-6300 6000);
WIRE 16 -1 (-6475 6050)(-6475 6000);
WIRE 16 -1 (-6300 6050)(-6475 6050);
WIRE 16 -1 (-6475 6100)(-6475 6050);
WIRE 16 -1 (-6475 6150)(-6475 6100);
WIRE 16 -1 (-6475 6100)(-6300 6100);
WIRE 16 -1 (-6475 6150)(-6300 6150);
WIRE 16 -1 (-6475 6200)(-6475 6150);
WIRE 16 -1 (-6475 6200)(-6300 6200);
WIRE 16 -1 (-6475 6250)(-6475 6200);
WIRE 16 -1 (-6475 6250)(-6300 6250);
WIRE 16 -1 (-6475 6300)(-6475 6250);
WIRE 16 -1 (-6300 6300)(-6475 6300);
WIRE 16 -1 (-6475 6350)(-6475 6300);
WIRE 16 -1 (-6475 6350)(-6300 6350);
WIRE 16 -1 (-5025 550)(-5025 500);
WIRE 16 -1 (-5200 550)(-5025 550);
WIRE 16 -1 (-5025 600)(-5025 550);
WIRE 16 -1 (-5025 500)(-5025 475);
WIRE 16 -1 (-5200 500)(-5025 500);
WIRE 16 -1 (-5200 600)(-5025 600);
WIRE 16 -1 (-5025 650)(-5025 600);
WIRE 16 -1 (-5200 650)(-5025 650);
WIRE 16 -1 (-5025 700)(-5025 650);
WIRE 16 -1 (-5200 700)(-5025 700);
WIRE 16 -1 (-5025 750)(-5025 700);
WIRE 16 -1 (-5200 750)(-5025 750);
WIRE 16 -1 (-5025 800)(-5025 750);
WIRE 16 -1 (-5200 800)(-5025 800);
WIRE 16 -1 (-5025 850)(-5025 800);
WIRE 16 -1 (-5200 850)(-5025 850);
WIRE 16 -1 (-5025 900)(-5025 850);
WIRE 16 -1 (-5200 900)(-5025 900);
WIRE 16 -1 (-5025 950)(-5025 900);
WIRE 16 -1 (-5200 950)(-5025 950);
WIRE 16 -1 (-5025 1000)(-5025 950);
WIRE 16 -1 (-5200 1000)(-5025 1000);
WIRE 16 -1 (-5025 1050)(-5025 1000);
WIRE 16 -1 (-5200 1050)(-5025 1050);
WIRE 16 -1 (-5025 1100)(-5025 1050);
WIRE 16 -1 (-5200 1100)(-5025 1100);
WIRE 16 -1 (-5025 1150)(-5025 1100);
WIRE 16 -1 (-5200 1150)(-5025 1150);
WIRE 16 -1 (-5025 1200)(-5025 1150);
WIRE 16 -1 (-5200 1200)(-5025 1200);
WIRE 16 -1 (-5025 1250)(-5025 1200);
WIRE 16 -1 (-5200 1250)(-5025 1250);
WIRE 16 -1 (-5025 1300)(-5025 1250);
WIRE 16 -1 (-5200 1300)(-5025 1300);
WIRE 16 -1 (-5025 1350)(-5025 1300);
WIRE 16 -1 (-5200 1350)(-5025 1350);
WIRE 16 -1 (-5025 1400)(-5025 1350);
WIRE 16 -1 (-5200 1400)(-5025 1400);
WIRE 16 -1 (-5025 1450)(-5025 1400);
WIRE 16 -1 (-5200 1450)(-5025 1450);
WIRE 16 -1 (-5025 1500)(-5025 1450);
WIRE 16 -1 (-5200 1500)(-5025 1500);
WIRE 16 -1 (-5025 1550)(-5025 1500);
WIRE 16 -1 (-5200 1550)(-5025 1550);
WIRE 16 -1 (-5025 1600)(-5025 1550);
WIRE 16 -1 (-5200 1600)(-5025 1600);
WIRE 16 -1 (-5025 1650)(-5025 1600);
WIRE 16 -1 (-5200 1650)(-5025 1650);
WIRE 16 -1 (-5025 1700)(-5025 1650);
WIRE 16 -1 (-5200 1700)(-5025 1700);
WIRE 16 -1 (-5025 1750)(-5025 1700);
WIRE 16 -1 (-5200 1750)(-5025 1750);
WIRE 16 -1 (-5025 1800)(-5025 1750);
WIRE 16 -1 (-5200 1800)(-5025 1800);
WIRE 16 -1 (-5025 1850)(-5025 1800);
WIRE 16 -1 (-5200 1850)(-5025 1850);
WIRE 16 -1 (-5025 1900)(-5025 1850);
WIRE 16 -1 (-5200 1900)(-5025 1900);
WIRE 16 -1 (-5025 1950)(-5025 1900);
WIRE 16 -1 (-5200 1950)(-5025 1950);
WIRE 16 -1 (-5025 2000)(-5025 1950);
WIRE 16 -1 (-5200 2000)(-5025 2000);
WIRE 16 -1 (-5025 2050)(-5025 2000);
WIRE 16 -1 (-5025 2100)(-5025 2050);
WIRE 16 -1 (-5200 2050)(-5025 2050);
WIRE 16 -1 (-5200 2100)(-5025 2100);
WIRE 16 -1 (-5025 2150)(-5025 2100);
WIRE 16 -1 (-5200 2150)(-5025 2150);
WIRE 16 -1 (-5025 2200)(-5025 2150);
WIRE 16 -1 (-5200 2200)(-5025 2200);
WIRE 16 -1 (-5025 2250)(-5025 2200);
WIRE 16 -1 (-5200 2250)(-5025 2250);
WIRE 16 -1 (-5025 2300)(-5025 2250);
WIRE 16 -1 (-5200 2300)(-5025 2300);
WIRE 16 -1 (-5025 2350)(-5025 2300);
WIRE 16 -1 (-5200 2350)(-5025 2350);
WIRE 16 -1 (-5025 2400)(-5025 2350);
WIRE 16 -1 (-5200 2400)(-5025 2400);
WIRE 16 -1 (-5025 2450)(-5025 2400);
WIRE 16 -1 (-5200 2450)(-5025 2450);
WIRE 16 -1 (-5025 2500)(-5025 2450);
WIRE 16 -1 (-5200 2500)(-5025 2500);
WIRE 16 -1 (-5025 2550)(-5025 2500);
WIRE 16 -1 (-5200 2550)(-5025 2550);
WIRE 16 -1 (-5025 2600)(-5025 2550);
WIRE 16 -1 (-5200 2600)(-5025 2600);
WIRE 16 -1 (-5025 2650)(-5025 2600);
WIRE 16 -1 (-5200 2650)(-5025 2650);
WIRE 16 -1 (-5025 2700)(-5025 2650);
WIRE 16 -1 (-5200 2700)(-5025 2700);
WIRE 16 -1 (-5025 2750)(-5025 2700);
WIRE 16 -1 (-5200 2750)(-5025 2750);
WIRE 16 -1 (-5025 2800)(-5025 2750);
WIRE 16 -1 (-5200 2800)(-5025 2800);
WIRE 16 -1 (-5025 2850)(-5025 2800);
WIRE 16 -1 (-5200 2850)(-5025 2850);
WIRE 16 -1 (-5025 2900)(-5025 2850);
WIRE 16 -1 (-5200 2900)(-5025 2900);
WIRE 16 -1 (-5025 2950)(-5025 2900);
WIRE 16 -1 (-5200 2950)(-5025 2950);
WIRE 16 -1 (-5025 3000)(-5025 2950);
WIRE 16 -1 (-5200 3000)(-5025 3000);
WIRE 16 -1 (-5025 3050)(-5025 3000);
WIRE 16 -1 (-5200 3050)(-5025 3050);
WIRE 16 -1 (-5025 3100)(-5025 3050);
WIRE 16 -1 (-5200 3100)(-5025 3100);
WIRE 16 -1 (-5025 3150)(-5025 3100);
WIRE 16 -1 (-5200 3150)(-5025 3150);
WIRE 16 -1 (-5025 3200)(-5025 3150);
WIRE 16 -1 (-5200 3200)(-5025 3200);
WIRE 16 -1 (-5025 3250)(-5025 3200);
WIRE 16 -1 (-5200 3250)(-5025 3250);
WIRE 16 -1 (-5025 3300)(-5025 3250);
WIRE 16 -1 (-5200 3300)(-5025 3300);
WIRE 16 -1 (-5025 3350)(-5025 3300);
WIRE 16 -1 (-5200 3350)(-5025 3350);
WIRE 16 -1 (-5025 3400)(-5025 3350);
WIRE 16 -1 (-5200 3400)(-5025 3400);
WIRE 16 -1 (-5025 3450)(-5025 3400);
WIRE 16 -1 (-5200 3450)(-5025 3450);
WIRE 16 -1 (-5025 3500)(-5025 3450);
WIRE 16 -1 (-5200 3500)(-5025 3500);
WIRE 16 -1 (-5025 3550)(-5025 3500);
WIRE 16 -1 (-5200 3550)(-5025 3550);
WIRE 16 -1 (-5025 3600)(-5025 3550);
WIRE 16 -1 (-5200 3600)(-5025 3600);
WIRE 16 -1 (-5025 3650)(-5025 3600);
WIRE 16 -1 (-5200 3650)(-5025 3650);
WIRE 16 -1 (-5025 3700)(-5025 3650);
WIRE 16 -1 (-5200 3700)(-5025 3700);
WIRE 16 -1 (-5025 3750)(-5025 3700);
WIRE 16 -1 (-5200 3750)(-5025 3750);
WIRE 16 -1 (-5025 3800)(-5025 3750);
WIRE 16 -1 (-5200 3800)(-5025 3800);
WIRE 16 -1 (-5025 3850)(-5025 3800);
WIRE 16 -1 (-5200 3850)(-5025 3850);
WIRE 16 -1 (-5025 3900)(-5025 3850);
WIRE 16 -1 (-5200 3900)(-5025 3900);
WIRE 16 -1 (-5025 3950)(-5025 3900);
WIRE 16 -1 (-5200 3950)(-5025 3950);
WIRE 16 -1 (-5025 4000)(-5025 3950);
WIRE 16 -1 (-5200 4000)(-5025 4000);
WIRE 16 -1 (-5025 4050)(-5025 4000);
WIRE 16 -1 (-5200 4050)(-5025 4050);
WIRE 16 -1 (-5025 4100)(-5025 4050);
WIRE 16 -1 (-5025 4150)(-5025 4100);
WIRE 16 -1 (-5200 4100)(-5025 4100);
WIRE 16 -1 (-5200 4150)(-5025 4150);
WIRE 16 -1 (-5025 4200)(-5025 4150);
WIRE 16 -1 (-5200 4200)(-5025 4200);
WIRE 16 -1 (-5025 4250)(-5025 4200);
WIRE 16 -1 (-5200 4250)(-5025 4250);
WIRE 16 -1 (-5025 4300)(-5025 4250);
WIRE 16 -1 (-5200 4300)(-5025 4300);
WIRE 16 -1 (-5025 4350)(-5025 4300);
WIRE 16 -1 (-5200 4350)(-5025 4350);
WIRE 16 -1 (-5025 4400)(-5025 4350);
WIRE 16 -1 (-5200 4400)(-5025 4400);
WIRE 16 -1 (-5025 4450)(-5025 4400);
WIRE 16 -1 (-5200 4450)(-5025 4450);
WIRE 16 -1 (-5025 4500)(-5025 4450);
WIRE 16 -1 (-5200 4500)(-5025 4500);
WIRE 16 -1 (-5025 4550)(-5025 4500);
WIRE 16 -1 (-5200 4550)(-5025 4550);
WIRE 16 -1 (-5025 4600)(-5025 4550);
WIRE 16 -1 (-5200 4600)(-5025 4600);
WIRE 16 -1 (-5025 4650)(-5025 4600);
WIRE 16 -1 (-5200 4650)(-5025 4650);
WIRE 16 -1 (-5025 4700)(-5025 4650);
WIRE 16 -1 (-5200 4700)(-5025 4700);
WIRE 16 -1 (-5025 4750)(-5025 4700);
WIRE 16 -1 (-5200 4750)(-5025 4750);
WIRE 16 -1 (-5025 4800)(-5025 4750);
WIRE 16 -1 (-5200 4800)(-5025 4800);
WIRE 16 -1 (-5025 4850)(-5025 4800);
WIRE 16 -1 (-5200 4850)(-5025 4850);
WIRE 16 -1 (-5025 4900)(-5025 4850);
WIRE 16 -1 (-5200 4900)(-5025 4900);
WIRE 16 -1 (-5025 4950)(-5025 4900);
WIRE 16 -1 (-5200 4950)(-5025 4950);
WIRE 16 -1 (-5025 5000)(-5025 4950);
WIRE 16 -1 (-5200 5000)(-5025 5000);
WIRE 16 -1 (-5025 5050)(-5025 5000);
WIRE 16 -1 (-5200 5050)(-5025 5050);
WIRE 16 -1 (-5025 5100)(-5025 5050);
WIRE 16 -1 (-5200 5100)(-5025 5100);
WIRE 16 -1 (-5025 5150)(-5025 5100);
WIRE 16 -1 (-5200 5150)(-5025 5150);
WIRE 16 -1 (-5025 5200)(-5025 5150);
WIRE 16 -1 (-5200 5200)(-5025 5200);
WIRE 16 -1 (-5025 5250)(-5025 5200);
WIRE 16 -1 (-5200 5250)(-5025 5250);
WIRE 16 -1 (-5025 5300)(-5025 5250);
WIRE 16 -1 (-5200 5300)(-5025 5300);
WIRE 16 -1 (-5025 5350)(-5025 5300);
WIRE 16 -1 (-5200 5350)(-5025 5350);
WIRE 16 -1 (-5025 5400)(-5025 5350);
WIRE 16 -1 (-5200 5400)(-5025 5400);
WIRE 16 -1 (-5025 5450)(-5025 5400);
WIRE 16 -1 (-5200 5450)(-5025 5450);
WIRE 16 -1 (-5025 5500)(-5025 5450);
WIRE 16 -1 (-5200 5500)(-5025 5500);
WIRE 16 -1 (-5025 5550)(-5025 5500);
WIRE 16 -1 (-5200 5550)(-5025 5550);
WIRE 16 -1 (-5025 5600)(-5025 5550);
WIRE 16 -1 (-5200 5600)(-5025 5600);
WIRE 16 -1 (-5025 5650)(-5025 5600);
WIRE 16 -1 (-5200 5650)(-5025 5650);
WIRE 16 -1 (-5025 5700)(-5025 5650);
WIRE 16 -1 (-5200 5700)(-5025 5700);
WIRE 16 -1 (-5025 5750)(-5025 5700);
WIRE 16 -1 (-5200 5750)(-5025 5750);
WIRE 16 -1 (-5025 5800)(-5025 5750);
WIRE 16 -1 (-5200 5800)(-5025 5800);
WIRE 16 -1 (-5025 5850)(-5025 5800);
WIRE 16 -1 (-5200 5850)(-5025 5850);
WIRE 16 -1 (-5025 5900)(-5025 5850);
WIRE 16 -1 (-5200 5900)(-5025 5900);
WIRE 16 -1 (-5025 5950)(-5025 5900);
WIRE 16 -1 (-5200 5950)(-5025 5950);
WIRE 16 -1 (-5025 6000)(-5025 5950);
WIRE 16 -1 (-5200 6000)(-5025 6000);
WIRE 16 -1 (-5025 6050)(-5025 6000);
WIRE 16 -1 (-5200 6050)(-5025 6050);
WIRE 16 -1 (-5025 6100)(-5025 6050);
WIRE 16 -1 (-5200 6100)(-5025 6100);
WIRE 16 -1 (-5025 6150)(-5025 6100);
WIRE 16 -1 (-5025 6200)(-5025 6150);
WIRE 16 -1 (-5200 6150)(-5025 6150);
WIRE 16 -1 (-5200 6200)(-5025 6200);
WIRE 16 -1 (-5025 6250)(-5025 6200);
WIRE 16 -1 (-5200 6250)(-5025 6250);
WIRE 16 -1 (-5025 6300)(-5025 6250);
WIRE 16 -1 (-5200 6300)(-5025 6300);
WIRE 16 -1 (-4400 575)(-4225 575);
WIRE 16 -1 (-4400 625)(-4400 575);
WIRE 16 -1 (-4400 575)(-4400 475);
WIRE 16 -1 (-4225 625)(-4400 625);
WIRE 16 -1 (-4400 675)(-4400 625);
WIRE 16 -1 (-4400 675)(-4225 675);
WIRE 16 -1 (-4400 725)(-4400 675);
WIRE 16 -1 (-4400 725)(-4225 725);
WIRE 16 -1 (-4400 775)(-4400 725);
WIRE 16 -1 (-4400 775)(-4225 775);
WIRE 16 -1 (-4400 825)(-4400 775);
WIRE 16 -1 (-4400 825)(-4225 825);
WIRE 16 -1 (-4400 875)(-4400 825);
WIRE 16 -1 (-4225 875)(-4400 875);
WIRE 16 -1 (-4400 925)(-4400 875);
WIRE 16 -1 (-4400 925)(-4225 925);
WIRE 16 -1 (-4400 975)(-4400 925);
WIRE 16 -1 (-4400 1025)(-4400 975);
WIRE 16 -1 (-4400 975)(-4225 975);
WIRE 16 -1 (-4400 1025)(-4225 1025);
WIRE 16 -1 (-4400 1075)(-4400 1025);
WIRE 16 -1 (-4400 1075)(-4225 1075);
WIRE 16 -1 (-4400 1125)(-4400 1075);
WIRE 16 -1 (-4225 1125)(-4400 1125);
WIRE 16 -1 (-4400 1175)(-4400 1125);
WIRE 16 -1 (-4400 1175)(-4225 1175);
WIRE 16 -1 (-4400 1225)(-4400 1175);
WIRE 16 -1 (-4400 1225)(-4225 1225);
WIRE 16 -1 (-4400 1275)(-4400 1225);
WIRE 16 -1 (-4400 1275)(-4225 1275);
WIRE 16 -1 (-4400 1325)(-4400 1275);
WIRE 16 -1 (-4400 1325)(-4225 1325);
WIRE 16 -1 (-4400 1375)(-4400 1325);
WIRE 16 -1 (-4225 1375)(-4400 1375);
WIRE 16 -1 (-4400 1425)(-4400 1375);
WIRE 16 -1 (-4400 1425)(-4225 1425);
WIRE 16 -1 (-4400 1475)(-4400 1425);
WIRE 16 -1 (-4400 1475)(-4225 1475);
WIRE 16 -1 (-4400 1525)(-4400 1475);
WIRE 16 -1 (-4400 1575)(-4400 1525);
WIRE 16 -1 (-4400 1525)(-4225 1525);
WIRE 16 -1 (-4400 1575)(-4225 1575);
WIRE 16 -1 (-4400 1625)(-4400 1575);
WIRE 16 -1 (-4225 1625)(-4400 1625);
WIRE 16 -1 (-4400 1675)(-4400 1625);
WIRE 16 -1 (-4400 1675)(-4225 1675);
WIRE 16 -1 (-4400 1725)(-4400 1675);
WIRE 16 -1 (-4400 1725)(-4225 1725);
WIRE 16 -1 (-4400 1775)(-4400 1725);
WIRE 16 -1 (-4400 1775)(-4225 1775);
WIRE 16 -1 (-4400 1825)(-4400 1775);
WIRE 16 -1 (-4400 1825)(-4225 1825);
WIRE 16 -1 (-4400 1875)(-4400 1825);
WIRE 16 -1 (-4225 1875)(-4400 1875);
WIRE 16 -1 (-4400 1925)(-4400 1875);
WIRE 16 -1 (-4400 1925)(-4225 1925);
WIRE 16 -1 (-4400 1975)(-4400 1925);
WIRE 16 -1 (-4400 1975)(-4225 1975);
WIRE 16 -1 (-4400 2025)(-4400 1975);
WIRE 16 -1 (-4400 2075)(-4400 2025);
WIRE 16 -1 (-4400 2025)(-4225 2025);
WIRE 16 -1 (-4400 2075)(-4225 2075);
WIRE 16 -1 (-4400 2125)(-4400 2075);
WIRE 16 -1 (-4400 2125)(-4225 2125);
WIRE 16 -1 (-4400 2175)(-4400 2125);
WIRE 16 -1 (-4225 2175)(-4400 2175);
WIRE 16 -1 (-4400 2225)(-4400 2175);
WIRE 16 -1 (-4400 2225)(-4225 2225);
WIRE 16 -1 (-4400 2275)(-4400 2225);
WIRE 16 -1 (-4400 2275)(-4225 2275);
WIRE 16 -1 (-4400 2325)(-4400 2275);
WIRE 16 -1 (-4400 2325)(-4225 2325);
WIRE 16 -1 (-4400 2375)(-4400 2325);
WIRE 16 -1 (-4400 2375)(-4225 2375);
WIRE 16 -1 (-4400 2425)(-4400 2375);
WIRE 16 -1 (-4225 2425)(-4400 2425);
WIRE 16 -1 (-4400 2475)(-4400 2425);
WIRE 16 -1 (-4400 2475)(-4225 2475);
WIRE 16 -1 (-4400 2525)(-4400 2475);
WIRE 16 -1 (-4400 2575)(-4400 2525);
WIRE 16 -1 (-4400 2525)(-4225 2525);
WIRE 16 -1 (-4400 2575)(-4225 2575);
WIRE 16 -1 (-4400 2625)(-4400 2575);
WIRE 16 -1 (-4400 2625)(-4225 2625);
WIRE 16 -1 (-4400 2675)(-4400 2625);
WIRE 16 -1 (-4225 2675)(-4400 2675);
WIRE 16 -1 (-4400 2725)(-4400 2675);
WIRE 16 -1 (-4400 2725)(-4225 2725);
WIRE 16 -1 (-4400 2775)(-4400 2725);
WIRE 16 -1 (-4400 2775)(-4225 2775);
WIRE 16 -1 (-4400 2825)(-4400 2775);
WIRE 16 -1 (-4400 2825)(-4225 2825);
WIRE 16 -1 (-4400 2875)(-4400 2825);
WIRE 16 -1 (-4400 2875)(-4225 2875);
WIRE 16 -1 (-4400 2925)(-4400 2875);
WIRE 16 -1 (-4225 2925)(-4400 2925);
WIRE 16 -1 (-4400 2975)(-4400 2925);
WIRE 16 -1 (-4400 2975)(-4225 2975);
WIRE 16 -1 (-4400 3025)(-4400 2975);
WIRE 16 -1 (-4400 3075)(-4400 3025);
WIRE 16 -1 (-4400 3025)(-4225 3025);
WIRE 16 -1 (-4400 3075)(-4225 3075);
WIRE 16 -1 (-4400 3125)(-4400 3075);
WIRE 16 -1 (-4400 3125)(-4225 3125);
WIRE 16 -1 (-4400 3175)(-4400 3125);
WIRE 16 -1 (-4225 3175)(-4400 3175);
WIRE 16 -1 (-4400 3225)(-4400 3175);
WIRE 16 -1 (-4400 3225)(-4225 3225);
WIRE 16 -1 (-4400 3275)(-4400 3225);
WIRE 16 -1 (-4400 3275)(-4225 3275);
WIRE 16 -1 (-4400 3325)(-4400 3275);
WIRE 16 -1 (-4400 3325)(-4225 3325);
WIRE 16 -1 (-4400 3375)(-4400 3325);
WIRE 16 -1 (-4400 3375)(-4225 3375);
WIRE 16 -1 (-4400 3425)(-4400 3375);
WIRE 16 -1 (-4225 3425)(-4400 3425);
WIRE 16 -1 (-4400 3475)(-4400 3425);
WIRE 16 -1 (-4400 3475)(-4225 3475);
WIRE 16 -1 (-4400 3525)(-4400 3475);
WIRE 16 -1 (-4400 3525)(-4225 3525);
WIRE 16 -1 (-4400 3575)(-4400 3525);
WIRE 16 -1 (-4400 3625)(-4400 3575);
WIRE 16 -1 (-4400 3575)(-4225 3575);
WIRE 16 -1 (-4400 3625)(-4225 3625);
WIRE 16 -1 (-4400 3675)(-4400 3625);
WIRE 16 -1 (-4225 3675)(-4400 3675);
WIRE 16 -1 (-4400 3725)(-4400 3675);
WIRE 16 -1 (-4400 3725)(-4225 3725);
WIRE 16 -1 (-4400 3775)(-4400 3725);
WIRE 16 -1 (-4400 3775)(-4225 3775);
WIRE 16 -1 (-4400 3825)(-4400 3775);
WIRE 16 -1 (-4400 3825)(-4225 3825);
WIRE 16 -1 (-4400 3875)(-4400 3825);
WIRE 16 -1 (-4400 3875)(-4225 3875);
WIRE 16 -1 (-4400 3925)(-4400 3875);
WIRE 16 -1 (-4225 3925)(-4400 3925);
WIRE 16 -1 (-4400 3975)(-4400 3925);
WIRE 16 -1 (-4400 3975)(-4225 3975);
WIRE 16 -1 (-4400 4025)(-4400 3975);
WIRE 16 -1 (-4400 4025)(-4225 4025);
WIRE 16 -1 (-4400 4075)(-4400 4025);
WIRE 16 -1 (-4400 4125)(-4400 4075);
WIRE 16 -1 (-4400 4075)(-4225 4075);
WIRE 16 -1 (-4400 4125)(-4225 4125);
WIRE 16 -1 (-4400 4175)(-4400 4125);
WIRE 16 -1 (-4400 4175)(-4225 4175);
WIRE 16 -1 (-4400 4225)(-4400 4175);
WIRE 16 -1 (-4225 4225)(-4400 4225);
WIRE 16 -1 (-4400 4275)(-4400 4225);
WIRE 16 -1 (-4400 4275)(-4225 4275);
WIRE 16 -1 (-4400 4325)(-4400 4275);
WIRE 16 -1 (-4400 4325)(-4225 4325);
WIRE 16 -1 (-4400 4375)(-4400 4325);
WIRE 16 -1 (-4400 4375)(-4225 4375);
WIRE 16 -1 (-4400 4425)(-4400 4375);
WIRE 16 -1 (-4400 4425)(-4225 4425);
WIRE 16 -1 (-4400 4475)(-4400 4425);
WIRE 16 -1 (-4225 4475)(-4400 4475);
WIRE 16 -1 (-4400 4525)(-4400 4475);
WIRE 16 -1 (-4400 4525)(-4225 4525);
WIRE 16 -1 (-4400 4575)(-4400 4525);
WIRE 16 -1 (-4400 4625)(-4400 4575);
WIRE 16 -1 (-4400 4575)(-4225 4575);
WIRE 16 -1 (-4400 4625)(-4225 4625);
WIRE 16 -1 (-4400 4675)(-4400 4625);
WIRE 16 -1 (-4400 4675)(-4225 4675);
WIRE 16 -1 (-4400 4725)(-4400 4675);
WIRE 16 -1 (-4225 4725)(-4400 4725);
WIRE 16 -1 (-4400 4775)(-4400 4725);
WIRE 16 -1 (-4400 4775)(-4225 4775);
WIRE 16 -1 (-4400 4825)(-4400 4775);
WIRE 16 -1 (-4400 4825)(-4225 4825);
WIRE 16 -1 (-4400 4875)(-4400 4825);
WIRE 16 -1 (-4400 4875)(-4225 4875);
WIRE 16 -1 (-4400 4925)(-4400 4875);
WIRE 16 -1 (-4400 4925)(-4225 4925);
WIRE 16 -1 (-4400 4975)(-4400 4925);
WIRE 16 -1 (-4225 4975)(-4400 4975);
WIRE 16 -1 (-4400 5025)(-4400 4975);
WIRE 16 -1 (-4400 5025)(-4225 5025);
WIRE 16 -1 (-4400 5075)(-4400 5025);
WIRE 16 -1 (-4400 5125)(-4400 5075);
WIRE 16 -1 (-4400 5075)(-4225 5075);
WIRE 16 -1 (-4400 5125)(-4225 5125);
WIRE 16 -1 (-4400 5175)(-4400 5125);
WIRE 16 -1 (-4400 5175)(-4225 5175);
WIRE 16 -1 (-4400 5225)(-4400 5175);
WIRE 16 -1 (-4225 5225)(-4400 5225);
WIRE 16 -1 (-4400 5275)(-4400 5225);
WIRE 16 -1 (-4400 5275)(-4225 5275);
WIRE 16 -1 (-4400 5325)(-4400 5275);
WIRE 16 -1 (-4400 5325)(-4225 5325);
WIRE 16 -1 (-4400 5375)(-4400 5325);
WIRE 16 -1 (-4400 5375)(-4225 5375);
WIRE 16 -1 (-4400 5425)(-4400 5375);
WIRE 16 -1 (-4400 5425)(-4225 5425);
WIRE 16 -1 (-4400 5475)(-4400 5425);
WIRE 16 -1 (-4225 5475)(-4400 5475);
WIRE 16 -1 (-4400 5525)(-4400 5475);
WIRE 16 -1 (-4400 5525)(-4225 5525);
WIRE 16 -1 (-4400 5575)(-4400 5525);
WIRE 16 -1 (-4400 5575)(-4225 5575);
WIRE 16 -1 (-4400 5625)(-4400 5575);
WIRE 16 -1 (-4400 5675)(-4400 5625);
WIRE 16 -1 (-4400 5625)(-4225 5625);
WIRE 16 -1 (-4400 5675)(-4225 5675);
WIRE 16 -1 (-4400 5725)(-4400 5675);
WIRE 16 -1 (-4225 5725)(-4400 5725);
WIRE 16 -1 (-4400 5775)(-4400 5725);
WIRE 16 -1 (-4400 5775)(-4225 5775);
WIRE 16 -1 (-4400 5825)(-4400 5775);
WIRE 16 -1 (-4400 5825)(-4225 5825);
WIRE 16 -1 (-4400 5875)(-4400 5825);
WIRE 16 -1 (-4400 5875)(-4225 5875);
WIRE 16 -1 (-4400 5925)(-4400 5875);
WIRE 16 -1 (-4400 5925)(-4225 5925);
WIRE 16 -1 (-4400 5975)(-4400 5925);
WIRE 16 -1 (-4225 5975)(-4400 5975);
WIRE 16 -1 (-4400 6025)(-4400 5975);
WIRE 16 -1 (-4400 6025)(-4225 6025);
WIRE 16 -1 (-4400 6075)(-4400 6025);
WIRE 16 -1 (-4400 6075)(-4225 6075);
WIRE 16 -1 (-4400 6125)(-4400 6075);
WIRE 16 -1 (-4400 6175)(-4400 6125);
WIRE 16 -1 (-4400 6125)(-4225 6125);
WIRE 16 -1 (-4400 6175)(-4225 6175);
WIRE 16 -1 (-4400 6225)(-4400 6175);
WIRE 16 -1 (-4225 6225)(-4400 6225);
WIRE 16 -1 (-4400 6275)(-4400 6225);
WIRE 16 -1 (-4400 6275)(-4225 6275);
WIRE 16 -1 (-3125 575)(-2950 575);
WIRE 16 -1 (-2950 625)(-2950 575);
WIRE 16 -1 (-2950 450)(-2950 575);
WIRE 16 -1 (-3125 625)(-2950 625);
WIRE 16 -1 (-2950 675)(-2950 625);
WIRE 16 -1 (-3125 675)(-2950 675);
WIRE 16 -1 (-2950 725)(-2950 675);
WIRE 16 -1 (-3125 725)(-2950 725);
WIRE 16 -1 (-2950 775)(-2950 725);
WIRE 16 -1 (-3125 775)(-2950 775);
WIRE 16 -1 (-2950 825)(-2950 775);
WIRE 16 -1 (-3125 825)(-2950 825);
WIRE 16 -1 (-2950 875)(-2950 825);
WIRE 16 -1 (-3125 875)(-2950 875);
WIRE 16 -1 (-2950 925)(-2950 875);
WIRE 16 -1 (-3125 925)(-2950 925);
WIRE 16 -1 (-2950 975)(-2950 925);
WIRE 16 -1 (-3125 975)(-2950 975);
WIRE 16 -1 (-2950 1025)(-2950 975);
WIRE 16 -1 (-3125 1025)(-2950 1025);
WIRE 16 -1 (-2950 1075)(-2950 1025);
WIRE 16 -1 (-3125 1075)(-2950 1075);
WIRE 16 -1 (-2950 1125)(-2950 1075);
WIRE 16 -1 (-3125 1125)(-2950 1125);
WIRE 16 -1 (-2950 1175)(-2950 1125);
WIRE 16 -1 (-3125 1175)(-2950 1175);
WIRE 16 -1 (-2950 1225)(-2950 1175);
WIRE 16 -1 (-3125 1225)(-2950 1225);
WIRE 16 -1 (-2950 1275)(-2950 1225);
WIRE 16 -1 (-3125 1275)(-2950 1275);
WIRE 16 -1 (-2950 1325)(-2950 1275);
WIRE 16 -1 (-3125 1325)(-2950 1325);
WIRE 16 -1 (-2950 1375)(-2950 1325);
WIRE 16 -1 (-3125 1375)(-2950 1375);
WIRE 16 -1 (-2950 1425)(-2950 1375);
WIRE 16 -1 (-3125 1425)(-2950 1425);
WIRE 16 -1 (-2950 1475)(-2950 1425);
WIRE 16 -1 (-3125 1475)(-2950 1475);
WIRE 16 -1 (-2950 1525)(-2950 1475);
WIRE 16 -1 (-3125 1525)(-2950 1525);
WIRE 16 -1 (-2950 1575)(-2950 1525);
WIRE 16 -1 (-3125 1575)(-2950 1575);
WIRE 16 -1 (-2950 1625)(-2950 1575);
WIRE 16 -1 (-3125 1625)(-2950 1625);
WIRE 16 -1 (-2950 1675)(-2950 1625);
WIRE 16 -1 (-3125 1675)(-2950 1675);
WIRE 16 -1 (-2950 1725)(-2950 1675);
WIRE 16 -1 (-3125 1725)(-2950 1725);
WIRE 16 -1 (-2950 1775)(-2950 1725);
WIRE 16 -1 (-3125 1775)(-2950 1775);
WIRE 16 -1 (-2950 1825)(-2950 1775);
WIRE 16 -1 (-3125 1825)(-2950 1825);
WIRE 16 -1 (-2950 1875)(-2950 1825);
WIRE 16 -1 (-3125 1875)(-2950 1875);
WIRE 16 -1 (-2950 1925)(-2950 1875);
WIRE 16 -1 (-3125 1925)(-2950 1925);
WIRE 16 -1 (-2950 1975)(-2950 1925);
WIRE 16 -1 (-3125 1975)(-2950 1975);
WIRE 16 -1 (-2950 2025)(-2950 1975);
WIRE 16 -1 (-3125 2025)(-2950 2025);
WIRE 16 -1 (-2950 2075)(-2950 2025);
WIRE 16 -1 (-2950 2125)(-2950 2075);
WIRE 16 -1 (-3125 2075)(-2950 2075);
WIRE 16 -1 (-3125 2125)(-2950 2125);
WIRE 16 -1 (-2950 2175)(-2950 2125);
WIRE 16 -1 (-3125 2175)(-2950 2175);
WIRE 16 -1 (-2950 2225)(-2950 2175);
WIRE 16 -1 (-3125 2225)(-2950 2225);
WIRE 16 -1 (-2950 2275)(-2950 2225);
WIRE 16 -1 (-3125 2275)(-2950 2275);
WIRE 16 -1 (-2950 2325)(-2950 2275);
WIRE 16 -1 (-3125 2325)(-2950 2325);
WIRE 16 -1 (-2950 2375)(-2950 2325);
WIRE 16 -1 (-3125 2375)(-2950 2375);
WIRE 16 -1 (-2950 2425)(-2950 2375);
WIRE 16 -1 (-3125 2425)(-2950 2425);
WIRE 16 -1 (-2950 2475)(-2950 2425);
WIRE 16 -1 (-3125 2475)(-2950 2475);
WIRE 16 -1 (-2950 2525)(-2950 2475);
WIRE 16 -1 (-3125 2525)(-2950 2525);
WIRE 16 -1 (-2950 2575)(-2950 2525);
WIRE 16 -1 (-3125 2575)(-2950 2575);
WIRE 16 -1 (-2950 2625)(-2950 2575);
WIRE 16 -1 (-3125 2625)(-2950 2625);
WIRE 16 -1 (-2950 2675)(-2950 2625);
WIRE 16 -1 (-3125 2675)(-2950 2675);
WIRE 16 -1 (-2950 2725)(-2950 2675);
WIRE 16 -1 (-3125 2725)(-2950 2725);
WIRE 16 -1 (-2950 2775)(-2950 2725);
WIRE 16 -1 (-3125 2775)(-2950 2775);
WIRE 16 -1 (-2950 2825)(-2950 2775);
WIRE 16 -1 (-3125 2825)(-2950 2825);
WIRE 16 -1 (-2950 2875)(-2950 2825);
WIRE 16 -1 (-3125 2875)(-2950 2875);
WIRE 16 -1 (-2950 2925)(-2950 2875);
WIRE 16 -1 (-3125 2925)(-2950 2925);
WIRE 16 -1 (-2950 2975)(-2950 2925);
WIRE 16 -1 (-3125 2975)(-2950 2975);
WIRE 16 -1 (-2950 3025)(-2950 2975);
WIRE 16 -1 (-3125 3025)(-2950 3025);
WIRE 16 -1 (-2950 3075)(-2950 3025);
WIRE 16 -1 (-3125 3075)(-2950 3075);
WIRE 16 -1 (-2950 3125)(-2950 3075);
WIRE 16 -1 (-3125 3125)(-2950 3125);
WIRE 16 -1 (-2950 3175)(-2950 3125);
WIRE 16 -1 (-3125 3175)(-2950 3175);
WIRE 16 -1 (-2950 3225)(-2950 3175);
WIRE 16 -1 (-3125 3225)(-2950 3225);
WIRE 16 -1 (-2950 3275)(-2950 3225);
WIRE 16 -1 (-3125 3275)(-2950 3275);
WIRE 16 -1 (-2950 3325)(-2950 3275);
WIRE 16 -1 (-3125 3325)(-2950 3325);
WIRE 16 -1 (-2950 3375)(-2950 3325);
WIRE 16 -1 (-3125 3375)(-2950 3375);
WIRE 16 -1 (-2950 3425)(-2950 3375);
WIRE 16 -1 (-3125 3425)(-2950 3425);
WIRE 16 -1 (-2950 3475)(-2950 3425);
WIRE 16 -1 (-3125 3475)(-2950 3475);
WIRE 16 -1 (-2950 3525)(-2950 3475);
WIRE 16 -1 (-3125 3525)(-2950 3525);
WIRE 16 -1 (-2950 3575)(-2950 3525);
WIRE 16 -1 (-3125 3575)(-2950 3575);
WIRE 16 -1 (-2950 3625)(-2950 3575);
WIRE 16 -1 (-3125 3625)(-2950 3625);
WIRE 16 -1 (-2950 3675)(-2950 3625);
WIRE 16 -1 (-3125 3675)(-2950 3675);
WIRE 16 -1 (-2950 3725)(-2950 3675);
WIRE 16 -1 (-3125 3725)(-2950 3725);
WIRE 16 -1 (-2950 3775)(-2950 3725);
WIRE 16 -1 (-3125 3775)(-2950 3775);
WIRE 16 -1 (-2950 3825)(-2950 3775);
WIRE 16 -1 (-3125 3825)(-2950 3825);
WIRE 16 -1 (-2950 3875)(-2950 3825);
WIRE 16 -1 (-3125 3875)(-2950 3875);
WIRE 16 -1 (-2950 3925)(-2950 3875);
WIRE 16 -1 (-3125 3925)(-2950 3925);
WIRE 16 -1 (-2950 3975)(-2950 3925);
WIRE 16 -1 (-3125 3975)(-2950 3975);
WIRE 16 -1 (-2950 4025)(-2950 3975);
WIRE 16 -1 (-3125 4025)(-2950 4025);
WIRE 16 -1 (-2950 4075)(-2950 4025);
WIRE 16 -1 (-3125 4075)(-2950 4075);
WIRE 16 -1 (-2950 4125)(-2950 4075);
WIRE 16 -1 (-2950 4175)(-2950 4125);
WIRE 16 -1 (-3125 4125)(-2950 4125);
WIRE 16 -1 (-3125 4175)(-2950 4175);
WIRE 16 -1 (-2950 4225)(-2950 4175);
WIRE 16 -1 (-3125 4225)(-2950 4225);
WIRE 16 -1 (-2950 4275)(-2950 4225);
WIRE 16 -1 (-3125 4275)(-2950 4275);
WIRE 16 -1 (-2950 4325)(-2950 4275);
WIRE 16 -1 (-3125 4325)(-2950 4325);
WIRE 16 -1 (-2950 4375)(-2950 4325);
WIRE 16 -1 (-3125 4375)(-2950 4375);
WIRE 16 -1 (-2950 4425)(-2950 4375);
WIRE 16 -1 (-3125 4425)(-2950 4425);
WIRE 16 -1 (-2950 4475)(-2950 4425);
WIRE 16 -1 (-3125 4475)(-2950 4475);
WIRE 16 -1 (-2950 4525)(-2950 4475);
WIRE 16 -1 (-3125 4525)(-2950 4525);
WIRE 16 -1 (-2950 4575)(-2950 4525);
WIRE 16 -1 (-3125 4575)(-2950 4575);
WIRE 16 -1 (-2950 4625)(-2950 4575);
WIRE 16 -1 (-3125 4625)(-2950 4625);
WIRE 16 -1 (-2950 4675)(-2950 4625);
WIRE 16 -1 (-3125 4675)(-2950 4675);
WIRE 16 -1 (-2950 4725)(-2950 4675);
WIRE 16 -1 (-3125 4725)(-2950 4725);
WIRE 16 -1 (-2950 4775)(-2950 4725);
WIRE 16 -1 (-3125 4775)(-2950 4775);
WIRE 16 -1 (-2950 4825)(-2950 4775);
WIRE 16 -1 (-3125 4825)(-2950 4825);
WIRE 16 -1 (-2950 4875)(-2950 4825);
WIRE 16 -1 (-3125 4875)(-2950 4875);
WIRE 16 -1 (-2950 4925)(-2950 4875);
WIRE 16 -1 (-3125 4925)(-2950 4925);
WIRE 16 -1 (-2950 4975)(-2950 4925);
WIRE 16 -1 (-3125 4975)(-2950 4975);
WIRE 16 -1 (-2950 5025)(-2950 4975);
WIRE 16 -1 (-3125 5025)(-2950 5025);
WIRE 16 -1 (-2950 5075)(-2950 5025);
WIRE 16 -1 (-3125 5075)(-2950 5075);
WIRE 16 -1 (-2950 5125)(-2950 5075);
WIRE 16 -1 (-3125 5125)(-2950 5125);
WIRE 16 -1 (-2950 5175)(-2950 5125);
WIRE 16 -1 (-3125 5175)(-2950 5175);
WIRE 16 -1 (-2950 5225)(-2950 5175);
WIRE 16 -1 (-3125 5225)(-2950 5225);
WIRE 16 -1 (-2950 5275)(-2950 5225);
WIRE 16 -1 (-3125 5275)(-2950 5275);
WIRE 16 -1 (-2950 5325)(-2950 5275);
WIRE 16 -1 (-3125 5325)(-2950 5325);
WIRE 16 -1 (-2950 5375)(-2950 5325);
WIRE 16 -1 (-3125 5375)(-2950 5375);
WIRE 16 -1 (-2950 5425)(-2950 5375);
WIRE 16 -1 (-3125 5425)(-2950 5425);
WIRE 16 -1 (-2950 5475)(-2950 5425);
WIRE 16 -1 (-3125 5475)(-2950 5475);
WIRE 16 -1 (-2950 5525)(-2950 5475);
WIRE 16 -1 (-3125 5525)(-2950 5525);
WIRE 16 -1 (-2950 5575)(-2950 5525);
WIRE 16 -1 (-3125 5575)(-2950 5575);
WIRE 16 -1 (-2950 5625)(-2950 5575);
WIRE 16 -1 (-3125 5625)(-2950 5625);
WIRE 16 -1 (-2950 5675)(-2950 5625);
WIRE 16 -1 (-3125 5675)(-2950 5675);
WIRE 16 -1 (-2950 5725)(-2950 5675);
WIRE 16 -1 (-3125 5725)(-2950 5725);
WIRE 16 -1 (-2950 5775)(-2950 5725);
WIRE 16 -1 (-3125 5775)(-2950 5775);
WIRE 16 -1 (-2950 5825)(-2950 5775);
WIRE 16 -1 (-3125 5825)(-2950 5825);
WIRE 16 -1 (-2950 5875)(-2950 5825);
WIRE 16 -1 (-3125 5875)(-2950 5875);
WIRE 16 -1 (-2950 5925)(-2950 5875);
WIRE 16 -1 (-3125 5925)(-2950 5925);
WIRE 16 -1 (-2950 5975)(-2950 5925);
WIRE 16 -1 (-3125 5975)(-2950 5975);
WIRE 16 -1 (-2950 6025)(-2950 5975);
WIRE 16 -1 (-3125 6025)(-2950 6025);
WIRE 16 -1 (-2950 6075)(-2950 6025);
WIRE 16 -1 (-3125 6075)(-2950 6075);
WIRE 16 -1 (-2950 6125)(-2950 6075);
WIRE 16 -1 (-3125 6125)(-2950 6125);
WIRE 16 -1 (-2950 6175)(-2950 6125);
WIRE 16 -1 (-2950 6225)(-2950 6175);
WIRE 16 -1 (-3125 6175)(-2950 6175);
WIRE 16 -1 (-3125 6225)(-2950 6225);
WIRE 16 -1 (-2950 6275)(-2950 6225);
WIRE 16 -1 (-3125 6275)(-2950 6275);
WIRE 16 -1 (-2950 6325)(-2950 6275);
WIRE 16 -1 (-3125 6325)(-2950 6325);
WIRE 16 -1 (-2950 6375)(-2950 6325);
WIRE 16 -1 (-3125 6375)(-2950 6375);
WIRE 16 -1 (-2325 550)(-2325 500);
WIRE 16 -1 (-2150 550)(-2325 550);
WIRE 16 -1 (-2325 600)(-2325 550);
WIRE 16 -1 (-2150 500)(-2325 500);
WIRE 16 -1 (-2325 500)(-2325 450);
WIRE 16 -1 (-2325 600)(-2150 600);
WIRE 16 -1 (-2325 650)(-2325 600);
WIRE 16 -1 (-2150 650)(-2325 650);
WIRE 16 -1 (-2325 700)(-2325 650);
WIRE 16 -1 (-2325 700)(-2150 700);
WIRE 16 -1 (-2325 750)(-2325 700);
WIRE 16 -1 (-2325 750)(-2150 750);
WIRE 16 -1 (-2325 800)(-2325 750);
WIRE 16 -1 (-2325 800)(-2150 800);
WIRE 16 -1 (-2325 850)(-2325 800);
WIRE 16 -1 (-2325 850)(-2150 850);
WIRE 16 -1 (-2325 900)(-2325 850);
WIRE 16 -1 (-2150 900)(-2325 900);
WIRE 16 -1 (-2325 950)(-2325 900);
WIRE 16 -1 (-2325 950)(-2150 950);
WIRE 16 -1 (-2325 1000)(-2325 950);
WIRE 16 -1 (-2325 1050)(-2325 1000);
WIRE 16 -1 (-2325 1000)(-2150 1000);
WIRE 16 -1 (-2325 1050)(-2150 1050);
WIRE 16 -1 (-2325 1100)(-2325 1050);
WIRE 16 -1 (-2325 1100)(-2150 1100);
WIRE 16 -1 (-2325 1150)(-2325 1100);
WIRE 16 -1 (-2150 1150)(-2325 1150);
WIRE 16 -1 (-2325 1200)(-2325 1150);
WIRE 16 -1 (-2325 1200)(-2150 1200);
WIRE 16 -1 (-2325 1250)(-2325 1200);
WIRE 16 -1 (-2325 1250)(-2150 1250);
WIRE 16 -1 (-2325 1300)(-2325 1250);
WIRE 16 -1 (-2325 1300)(-2150 1300);
WIRE 16 -1 (-2325 1350)(-2325 1300);
WIRE 16 -1 (-2325 1350)(-2150 1350);
WIRE 16 -1 (-2325 1400)(-2325 1350);
WIRE 16 -1 (-2150 1400)(-2325 1400);
WIRE 16 -1 (-2325 1450)(-2325 1400);
WIRE 16 -1 (-2325 1450)(-2150 1450);
WIRE 16 -1 (-2325 1500)(-2325 1450);
WIRE 16 -1 (-2325 1550)(-2325 1500);
WIRE 16 -1 (-2325 1500)(-2150 1500);
WIRE 16 -1 (-2325 1550)(-2150 1550);
WIRE 16 -1 (-2325 1600)(-2325 1550);
WIRE 16 -1 (-2325 1600)(-2150 1600);
WIRE 16 -1 (-2325 1650)(-2325 1600);
WIRE 16 -1 (-2150 1650)(-2325 1650);
WIRE 16 -1 (-2325 1700)(-2325 1650);
WIRE 16 -1 (-2325 1700)(-2150 1700);
WIRE 16 -1 (-2325 1750)(-2325 1700);
WIRE 16 -1 (-2325 1750)(-2150 1750);
WIRE 16 -1 (-2325 1800)(-2325 1750);
WIRE 16 -1 (-2325 1800)(-2150 1800);
WIRE 16 -1 (-2325 1850)(-2325 1800);
WIRE 16 -1 (-2325 1850)(-2150 1850);
WIRE 16 -1 (-2325 1900)(-2325 1850);
WIRE 16 -1 (-2150 1900)(-2325 1900);
WIRE 16 -1 (-2325 1950)(-2325 1900);
WIRE 16 -1 (-2325 1950)(-2150 1950);
WIRE 16 -1 (-2325 2000)(-2325 1950);
WIRE 16 -1 (-2325 2050)(-2325 2000);
WIRE 16 -1 (-2325 2000)(-2150 2000);
WIRE 16 -1 (-2325 2050)(-2150 2050);
WIRE 16 -1 (-2325 2100)(-2325 2050);
WIRE 16 -1 (-2325 2100)(-2150 2100);
WIRE 16 -1 (-2325 2150)(-2325 2100);
WIRE 16 -1 (-2325 2150)(-2150 2150);
WIRE 16 -1 (-2325 2200)(-2325 2150);
WIRE 16 -1 (-2150 2200)(-2325 2200);
WIRE 16 -1 (-2325 2250)(-2325 2200);
WIRE 16 -1 (-2325 2250)(-2150 2250);
WIRE 16 -1 (-2325 2300)(-2325 2250);
WIRE 16 -1 (-2325 2300)(-2150 2300);
WIRE 16 -1 (-2325 2350)(-2325 2300);
WIRE 16 -1 (-2325 2350)(-2150 2350);
WIRE 16 -1 (-2325 2400)(-2325 2350);
WIRE 16 -1 (-2325 2400)(-2150 2400);
WIRE 16 -1 (-2325 2450)(-2325 2400);
WIRE 16 -1 (-2150 2450)(-2325 2450);
WIRE 16 -1 (-2325 2500)(-2325 2450);
WIRE 16 -1 (-2325 2500)(-2150 2500);
WIRE 16 -1 (-2325 2550)(-2325 2500);
WIRE 16 -1 (-2325 2600)(-2325 2550);
WIRE 16 -1 (-2325 2550)(-2150 2550);
WIRE 16 -1 (-2325 2600)(-2150 2600);
WIRE 16 -1 (-2325 2650)(-2325 2600);
WIRE 16 -1 (-2325 2650)(-2150 2650);
WIRE 16 -1 (-2325 2700)(-2325 2650);
WIRE 16 -1 (-2150 2700)(-2325 2700);
WIRE 16 -1 (-2325 2750)(-2325 2700);
WIRE 16 -1 (-2325 2750)(-2150 2750);
WIRE 16 -1 (-2325 2800)(-2325 2750);
WIRE 16 -1 (-2325 2800)(-2150 2800);
WIRE 16 -1 (-2325 2850)(-2325 2800);
WIRE 16 -1 (-2325 2850)(-2150 2850);
WIRE 16 -1 (-2325 2900)(-2325 2850);
WIRE 16 -1 (-2325 2900)(-2150 2900);
WIRE 16 -1 (-2325 2950)(-2325 2900);
WIRE 16 -1 (-2150 2950)(-2325 2950);
WIRE 16 -1 (-2325 3000)(-2325 2950);
WIRE 16 -1 (-2325 3000)(-2150 3000);
WIRE 16 -1 (-2325 3050)(-2325 3000);
WIRE 16 -1 (-2325 3100)(-2325 3050);
WIRE 16 -1 (-2325 3050)(-2150 3050);
WIRE 16 -1 (-2325 3100)(-2150 3100);
WIRE 16 -1 (-2325 3150)(-2325 3100);
WIRE 16 -1 (-2325 3150)(-2150 3150);
WIRE 16 -1 (-2325 3200)(-2325 3150);
WIRE 16 -1 (-2150 3200)(-2325 3200);
WIRE 16 -1 (-2325 3250)(-2325 3200);
WIRE 16 -1 (-2325 3250)(-2150 3250);
WIRE 16 -1 (-2325 3300)(-2325 3250);
WIRE 16 -1 (-2325 3300)(-2150 3300);
WIRE 16 -1 (-2325 3350)(-2325 3300);
WIRE 16 -1 (-2325 3350)(-2150 3350);
WIRE 16 -1 (-2325 3400)(-2325 3350);
WIRE 16 -1 (-2325 3400)(-2150 3400);
WIRE 16 -1 (-2325 3450)(-2325 3400);
WIRE 16 -1 (-2150 3450)(-2325 3450);
WIRE 16 -1 (-2325 3500)(-2325 3450);
WIRE 16 -1 (-2325 3500)(-2150 3500);
WIRE 16 -1 (-2325 3550)(-2325 3500);
WIRE 16 -1 (-2325 3600)(-2325 3550);
WIRE 16 -1 (-2325 3550)(-2150 3550);
WIRE 16 -1 (-2325 3600)(-2150 3600);
WIRE 16 -1 (-2325 3650)(-2325 3600);
WIRE 16 -1 (-2325 3650)(-2150 3650);
WIRE 16 -1 (-2325 3700)(-2325 3650);
WIRE 16 -1 (-2150 3700)(-2325 3700);
WIRE 16 -1 (-2325 3750)(-2325 3700);
WIRE 16 -1 (-2325 3750)(-2150 3750);
WIRE 16 -1 (-2325 3800)(-2325 3750);
WIRE 16 -1 (-2325 3800)(-2150 3800);
WIRE 16 -1 (-2325 3850)(-2325 3800);
WIRE 16 -1 (-2325 3850)(-2150 3850);
WIRE 16 -1 (-2325 3900)(-2325 3850);
WIRE 16 -1 (-2325 3900)(-2150 3900);
WIRE 16 -1 (-2325 3950)(-2325 3900);
WIRE 16 -1 (-2150 3950)(-2325 3950);
WIRE 16 -1 (-2325 4000)(-2325 3950);
WIRE 16 -1 (-2325 4000)(-2150 4000);
WIRE 16 -1 (-2325 4050)(-2325 4000);
WIRE 16 -1 (-2325 4100)(-2325 4050);
WIRE 16 -1 (-2325 4050)(-2150 4050);
WIRE 16 -1 (-2325 4100)(-2150 4100);
WIRE 16 -1 (-2325 4150)(-2325 4100);
WIRE 16 -1 (-2325 4150)(-2150 4150);
WIRE 16 -1 (-2325 4200)(-2325 4150);
WIRE 16 -1 (-2325 4200)(-2150 4200);
WIRE 16 -1 (-2325 4250)(-2325 4200);
WIRE 16 -1 (-2150 4250)(-2325 4250);
WIRE 16 -1 (-2325 4300)(-2325 4250);
WIRE 16 -1 (-2325 4300)(-2150 4300);
WIRE 16 -1 (-2325 4350)(-2325 4300);
WIRE 16 -1 (-2325 4350)(-2150 4350);
WIRE 16 -1 (-2325 4400)(-2325 4350);
WIRE 16 -1 (-2325 4400)(-2150 4400);
WIRE 16 -1 (-2325 4450)(-2325 4400);
WIRE 16 -1 (-2325 4450)(-2150 4450);
WIRE 16 -1 (-2325 4500)(-2325 4450);
WIRE 16 -1 (-2150 4500)(-2325 4500);
WIRE 16 -1 (-2325 4550)(-2325 4500);
WIRE 16 -1 (-2325 4550)(-2150 4550);
WIRE 16 -1 (-2325 4600)(-2325 4550);
WIRE 16 -1 (-2325 4650)(-2325 4600);
WIRE 16 -1 (-2325 4600)(-2150 4600);
WIRE 16 -1 (-2325 4650)(-2150 4650);
WIRE 16 -1 (-2325 4700)(-2325 4650);
WIRE 16 -1 (-2325 4700)(-2150 4700);
WIRE 16 -1 (-2325 4750)(-2325 4700);
WIRE 16 -1 (-2150 4750)(-2325 4750);
WIRE 16 -1 (-2325 4800)(-2325 4750);
WIRE 16 -1 (-2325 4800)(-2150 4800);
WIRE 16 -1 (-2325 4850)(-2325 4800);
WIRE 16 -1 (-2325 4850)(-2150 4850);
WIRE 16 -1 (-2325 4900)(-2325 4850);
WIRE 16 -1 (-2325 4900)(-2150 4900);
WIRE 16 -1 (-2325 4950)(-2325 4900);
WIRE 16 -1 (-2325 4950)(-2150 4950);
WIRE 16 -1 (-2325 5000)(-2325 4950);
WIRE 16 -1 (-2150 5000)(-2325 5000);
WIRE 16 -1 (-2325 5050)(-2325 5000);
WIRE 16 -1 (-2325 5050)(-2150 5050);
WIRE 16 -1 (-2325 5100)(-2325 5050);
WIRE 16 -1 (-2325 5150)(-2325 5100);
WIRE 16 -1 (-2325 5100)(-2150 5100);
WIRE 16 -1 (-2325 5150)(-2150 5150);
WIRE 16 -1 (-2325 5200)(-2325 5150);
WIRE 16 -1 (-2325 5200)(-2150 5200);
WIRE 16 -1 (-2325 5250)(-2325 5200);
WIRE 16 -1 (-2150 5250)(-2325 5250);
WIRE 16 -1 (-2325 5300)(-2325 5250);
WIRE 16 -1 (-2325 5300)(-2150 5300);
WIRE 16 -1 (-2325 5350)(-2325 5300);
WIRE 16 -1 (-2325 5350)(-2150 5350);
WIRE 16 -1 (-2325 5400)(-2325 5350);
WIRE 16 -1 (-2325 5400)(-2150 5400);
WIRE 16 -1 (-2325 5450)(-2325 5400);
WIRE 16 -1 (-2325 5450)(-2150 5450);
WIRE 16 -1 (-2325 5500)(-2325 5450);
WIRE 16 -1 (-2150 5500)(-2325 5500);
WIRE 16 -1 (-2325 5550)(-2325 5500);
WIRE 16 -1 (-2325 5550)(-2150 5550);
WIRE 16 -1 (-2325 5600)(-2325 5550);
WIRE 16 -1 (-2325 5650)(-2325 5600);
WIRE 16 -1 (-2325 5600)(-2150 5600);
WIRE 16 -1 (-2325 5650)(-2150 5650);
WIRE 16 -1 (-2325 5700)(-2325 5650);
WIRE 16 -1 (-2325 5700)(-2150 5700);
WIRE 16 -1 (-2325 5750)(-2325 5700);
WIRE 16 -1 (-2150 5750)(-2325 5750);
WIRE 16 -1 (-2325 5800)(-2325 5750);
WIRE 16 -1 (-2325 5800)(-2150 5800);
WIRE 16 -1 (-2325 5850)(-2325 5800);
WIRE 16 -1 (-2325 5850)(-2150 5850);
WIRE 16 -1 (-2325 5900)(-2325 5850);
WIRE 16 -1 (-2325 5900)(-2150 5900);
WIRE 16 -1 (-2325 5950)(-2325 5900);
WIRE 16 -1 (-2325 5950)(-2150 5950);
WIRE 16 -1 (-2325 6000)(-2325 5950);
WIRE 16 -1 (-2150 6000)(-2325 6000);
WIRE 16 -1 (-2325 6050)(-2325 6000);
WIRE 16 -1 (-2325 6050)(-2150 6050);
WIRE 16 -1 (-2325 6100)(-2325 6050);
WIRE 16 -1 (-2325 6150)(-2325 6100);
WIRE 16 -1 (-2325 6100)(-2150 6100);
WIRE 16 -1 (-2325 6150)(-2150 6150);
WIRE 16 -1 (-2325 6200)(-2325 6150);
WIRE 16 -1 (-2325 6200)(-2150 6200);
WIRE 16 -1 (-2325 6250)(-2325 6200);
WIRE 16 -1 (-2150 6250)(-2325 6250);
WIRE 16 -1 (-2325 6300)(-2325 6250);
WIRE 16 -1 (-2325 6300)(-2150 6300);
WIRE 16 -1 (-1050 500)(-875 500);
WIRE 16 -1 (-875 550)(-875 500);
WIRE 16 -1 (-875 450)(-875 500);
WIRE 16 -1 (-1050 550)(-875 550);
WIRE 16 -1 (-875 600)(-875 550);
WIRE 16 -1 (-1050 600)(-875 600);
WIRE 16 -1 (-875 650)(-875 600);
WIRE 16 -1 (-1050 650)(-875 650);
WIRE 16 -1 (-875 700)(-875 650);
WIRE 16 -1 (-1050 700)(-875 700);
WIRE 16 -1 (-875 750)(-875 700);
WIRE 16 -1 (-1050 750)(-875 750);
WIRE 16 -1 (-875 800)(-875 750);
WIRE 16 -1 (-1050 800)(-875 800);
WIRE 16 -1 (-875 850)(-875 800);
WIRE 16 -1 (-1050 850)(-875 850);
WIRE 16 -1 (-875 900)(-875 850);
WIRE 16 -1 (-1050 900)(-875 900);
WIRE 16 -1 (-875 950)(-875 900);
WIRE 16 -1 (-1050 950)(-875 950);
WIRE 16 -1 (-875 1000)(-875 950);
WIRE 16 -1 (-1050 1000)(-875 1000);
WIRE 16 -1 (-875 1050)(-875 1000);
WIRE 16 -1 (-1050 1050)(-875 1050);
WIRE 16 -1 (-875 1100)(-875 1050);
WIRE 16 -1 (-1050 1100)(-875 1100);
WIRE 16 -1 (-875 1150)(-875 1100);
WIRE 16 -1 (-1050 1150)(-875 1150);
WIRE 16 -1 (-875 1200)(-875 1150);
WIRE 16 -1 (-1050 1200)(-875 1200);
WIRE 16 -1 (-875 1250)(-875 1200);
WIRE 16 -1 (-1050 1250)(-875 1250);
WIRE 16 -1 (-875 1300)(-875 1250);
WIRE 16 -1 (-1050 1300)(-875 1300);
WIRE 16 -1 (-875 1350)(-875 1300);
WIRE 16 -1 (-1050 1350)(-875 1350);
WIRE 16 -1 (-875 1400)(-875 1350);
WIRE 16 -1 (-1050 1400)(-875 1400);
WIRE 16 -1 (-875 1450)(-875 1400);
WIRE 16 -1 (-1050 1450)(-875 1450);
WIRE 16 -1 (-875 1500)(-875 1450);
WIRE 16 -1 (-1050 1500)(-875 1500);
WIRE 16 -1 (-875 1550)(-875 1500);
WIRE 16 -1 (-1050 1550)(-875 1550);
WIRE 16 -1 (-875 1600)(-875 1550);
WIRE 16 -1 (-1050 1600)(-875 1600);
WIRE 16 -1 (-875 1650)(-875 1600);
WIRE 16 -1 (-1050 1650)(-875 1650);
WIRE 16 -1 (-875 1700)(-875 1650);
WIRE 16 -1 (-1050 1700)(-875 1700);
WIRE 16 -1 (-875 1750)(-875 1700);
WIRE 16 -1 (-1050 1750)(-875 1750);
WIRE 16 -1 (-875 1800)(-875 1750);
WIRE 16 -1 (-1050 1800)(-875 1800);
WIRE 16 -1 (-875 1850)(-875 1800);
WIRE 16 -1 (-1050 1850)(-875 1850);
WIRE 16 -1 (-875 1900)(-875 1850);
WIRE 16 -1 (-1050 1900)(-875 1900);
WIRE 16 -1 (-875 1950)(-875 1900);
WIRE 16 -1 (-1050 1950)(-875 1950);
WIRE 16 -1 (-875 2000)(-875 1950);
WIRE 16 -1 (-1050 2000)(-875 2000);
WIRE 16 -1 (-875 2050)(-875 2000);
WIRE 16 -1 (-875 2100)(-875 2050);
WIRE 16 -1 (-1050 2050)(-875 2050);
WIRE 16 -1 (-1050 2100)(-875 2100);
WIRE 16 -1 (-875 2150)(-875 2100);
WIRE 16 -1 (-1050 2150)(-875 2150);
WIRE 16 -1 (-875 2200)(-875 2150);
WIRE 16 -1 (-1050 2200)(-875 2200);
WIRE 16 -1 (-875 2250)(-875 2200);
WIRE 16 -1 (-1050 2250)(-875 2250);
WIRE 16 -1 (-875 2300)(-875 2250);
WIRE 16 -1 (-1050 2300)(-875 2300);
WIRE 16 -1 (-875 2350)(-875 2300);
WIRE 16 -1 (-1050 2350)(-875 2350);
WIRE 16 -1 (-875 2400)(-875 2350);
WIRE 16 -1 (-1050 2400)(-875 2400);
WIRE 16 -1 (-875 2450)(-875 2400);
WIRE 16 -1 (-1050 2450)(-875 2450);
WIRE 16 -1 (-875 2500)(-875 2450);
WIRE 16 -1 (-1050 2500)(-875 2500);
WIRE 16 -1 (-875 2550)(-875 2500);
WIRE 16 -1 (-1050 2550)(-875 2550);
WIRE 16 -1 (-875 2600)(-875 2550);
WIRE 16 -1 (-1050 2600)(-875 2600);
WIRE 16 -1 (-875 2650)(-875 2600);
WIRE 16 -1 (-1050 2650)(-875 2650);
WIRE 16 -1 (-875 2700)(-875 2650);
WIRE 16 -1 (-1050 2700)(-875 2700);
WIRE 16 -1 (-875 2750)(-875 2700);
WIRE 16 -1 (-1050 2750)(-875 2750);
WIRE 16 -1 (-875 2800)(-875 2750);
WIRE 16 -1 (-1050 2800)(-875 2800);
WIRE 16 -1 (-875 2850)(-875 2800);
WIRE 16 -1 (-1050 2850)(-875 2850);
WIRE 16 -1 (-875 2900)(-875 2850);
WIRE 16 -1 (-1050 2900)(-875 2900);
WIRE 16 -1 (-875 2950)(-875 2900);
WIRE 16 -1 (-1050 2950)(-875 2950);
WIRE 16 -1 (-875 3000)(-875 2950);
WIRE 16 -1 (-1050 3000)(-875 3000);
WIRE 16 -1 (-875 3050)(-875 3000);
WIRE 16 -1 (-1050 3050)(-875 3050);
WIRE 16 -1 (-875 3100)(-875 3050);
WIRE 16 -1 (-1050 3100)(-875 3100);
WIRE 16 -1 (-875 3150)(-875 3100);
WIRE 16 -1 (-1050 3150)(-875 3150);
WIRE 16 -1 (-875 3200)(-875 3150);
WIRE 16 -1 (-1050 3200)(-875 3200);
WIRE 16 -1 (-875 3250)(-875 3200);
WIRE 16 -1 (-1050 3250)(-875 3250);
WIRE 16 -1 (-875 3300)(-875 3250);
WIRE 16 -1 (-1050 3300)(-875 3300);
WIRE 16 -1 (-875 3350)(-875 3300);
WIRE 16 -1 (-1050 3350)(-875 3350);
WIRE 16 -1 (-875 3400)(-875 3350);
WIRE 16 -1 (-1050 3400)(-875 3400);
WIRE 16 -1 (-875 3450)(-875 3400);
WIRE 16 -1 (-1050 3450)(-875 3450);
WIRE 16 -1 (-875 3500)(-875 3450);
WIRE 16 -1 (-1050 3500)(-875 3500);
WIRE 16 -1 (-875 3550)(-875 3500);
WIRE 16 -1 (-1050 3550)(-875 3550);
WIRE 16 -1 (-875 3600)(-875 3550);
WIRE 16 -1 (-1050 3600)(-875 3600);
WIRE 16 -1 (-875 3650)(-875 3600);
WIRE 16 -1 (-1050 3650)(-875 3650);
WIRE 16 -1 (-875 3700)(-875 3650);
WIRE 16 -1 (-1050 3700)(-875 3700);
WIRE 16 -1 (-875 3750)(-875 3700);
WIRE 16 -1 (-1050 3750)(-875 3750);
WIRE 16 -1 (-875 3800)(-875 3750);
WIRE 16 -1 (-1050 3800)(-875 3800);
WIRE 16 -1 (-875 3850)(-875 3800);
WIRE 16 -1 (-1050 3850)(-875 3850);
WIRE 16 -1 (-875 3900)(-875 3850);
WIRE 16 -1 (-1050 3900)(-875 3900);
WIRE 16 -1 (-875 3950)(-875 3900);
WIRE 16 -1 (-1050 3950)(-875 3950);
WIRE 16 -1 (-875 4000)(-875 3950);
WIRE 16 -1 (-1050 4000)(-875 4000);
WIRE 16 -1 (-875 4050)(-875 4000);
WIRE 16 -1 (-1050 4050)(-875 4050);
WIRE 16 -1 (-875 4100)(-875 4050);
WIRE 16 -1 (-875 4150)(-875 4100);
WIRE 16 -1 (-1050 4100)(-875 4100);
WIRE 16 -1 (-1050 4150)(-875 4150);
WIRE 16 -1 (-875 4200)(-875 4150);
WIRE 16 -1 (-1050 4200)(-875 4200);
WIRE 16 -1 (-875 4250)(-875 4200);
WIRE 16 -1 (-1050 4250)(-875 4250);
WIRE 16 -1 (-875 4300)(-875 4250);
WIRE 16 -1 (-1050 4300)(-875 4300);
WIRE 16 -1 (-875 4350)(-875 4300);
WIRE 16 -1 (-1050 4350)(-875 4350);
WIRE 16 -1 (-875 4400)(-875 4350);
WIRE 16 -1 (-1050 4400)(-875 4400);
WIRE 16 -1 (-875 4450)(-875 4400);
WIRE 16 -1 (-1050 4450)(-875 4450);
WIRE 16 -1 (-875 4500)(-875 4450);
WIRE 16 -1 (-1050 4500)(-875 4500);
WIRE 16 -1 (-875 4550)(-875 4500);
WIRE 16 -1 (-1050 4550)(-875 4550);
WIRE 16 -1 (-875 4600)(-875 4550);
WIRE 16 -1 (-1050 4600)(-875 4600);
WIRE 16 -1 (-875 4650)(-875 4600);
WIRE 16 -1 (-1050 4650)(-875 4650);
WIRE 16 -1 (-875 4700)(-875 4650);
WIRE 16 -1 (-1050 4700)(-875 4700);
WIRE 16 -1 (-875 4750)(-875 4700);
WIRE 16 -1 (-1050 4750)(-875 4750);
WIRE 16 -1 (-875 4800)(-875 4750);
WIRE 16 -1 (-1050 4800)(-875 4800);
WIRE 16 -1 (-875 4850)(-875 4800);
WIRE 16 -1 (-1050 4850)(-875 4850);
WIRE 16 -1 (-875 4900)(-875 4850);
WIRE 16 -1 (-1050 4900)(-875 4900);
WIRE 16 -1 (-875 4950)(-875 4900);
WIRE 16 -1 (-1050 4950)(-875 4950);
WIRE 16 -1 (-875 5000)(-875 4950);
WIRE 16 -1 (-1050 5000)(-875 5000);
WIRE 16 -1 (-875 5050)(-875 5000);
WIRE 16 -1 (-1050 5050)(-875 5050);
WIRE 16 -1 (-875 5100)(-875 5050);
WIRE 16 -1 (-1050 5100)(-875 5100);
WIRE 16 -1 (-875 5150)(-875 5100);
WIRE 16 -1 (-1050 5150)(-875 5150);
WIRE 16 -1 (-875 5200)(-875 5150);
WIRE 16 -1 (-1050 5200)(-875 5200);
WIRE 16 -1 (-875 5250)(-875 5200);
WIRE 16 -1 (-1050 5250)(-875 5250);
WIRE 16 -1 (-875 5300)(-875 5250);
WIRE 16 -1 (-1050 5300)(-875 5300);
WIRE 16 -1 (-875 5350)(-875 5300);
WIRE 16 -1 (-1050 5350)(-875 5350);
WIRE 16 -1 (-875 5400)(-875 5350);
WIRE 16 -1 (-1050 5400)(-875 5400);
WIRE 16 -1 (-875 5450)(-875 5400);
WIRE 16 -1 (-1050 5450)(-875 5450);
WIRE 16 -1 (-875 5500)(-875 5450);
WIRE 16 -1 (-1050 5500)(-875 5500);
WIRE 16 -1 (-875 5550)(-875 5500);
WIRE 16 -1 (-1050 5550)(-875 5550);
WIRE 16 -1 (-875 5600)(-875 5550);
WIRE 16 -1 (-1050 5600)(-875 5600);
WIRE 16 -1 (-875 5650)(-875 5600);
WIRE 16 -1 (-1050 5650)(-875 5650);
WIRE 16 -1 (-875 5700)(-875 5650);
WIRE 16 -1 (-1050 5700)(-875 5700);
WIRE 16 -1 (-875 5750)(-875 5700);
WIRE 16 -1 (-1050 5750)(-875 5750);
WIRE 16 -1 (-875 5800)(-875 5750);
WIRE 16 -1 (-1050 5800)(-875 5800);
WIRE 16 -1 (-875 5850)(-875 5800);
WIRE 16 -1 (-1050 5850)(-875 5850);
WIRE 16 -1 (-875 5900)(-875 5850);
WIRE 16 -1 (-1050 5900)(-875 5900);
WIRE 16 -1 (-875 5950)(-875 5900);
WIRE 16 -1 (-1050 5950)(-875 5950);
WIRE 16 -1 (-875 6000)(-875 5950);
WIRE 16 -1 (-1050 6000)(-875 6000);
WIRE 16 -1 (-875 6050)(-875 6000);
WIRE 16 -1 (-1050 6050)(-875 6050);
WIRE 16 -1 (-875 6100)(-875 6050);
WIRE 16 -1 (-1050 6100)(-875 6100);
WIRE 16 -1 (-875 6150)(-875 6100);
WIRE 16 -1 (-875 6200)(-875 6150);
WIRE 16 -1 (-1050 6150)(-875 6150);
WIRE 16 -1 (-1050 6200)(-875 6200);
WIRE 16 -1 (-875 6250)(-875 6200);
WIRE 16 -1 (-1050 6250)(-875 6250);
WIRE 16 -1 (-875 6300)(-875 6250);
WIRE 16 -1 (-1050 6300)(-875 6300);
DOT 1 (-6475 3500);
DOT 1 (-8500 4900);
DOT 1 (-6475 4150);
DOT 1 (-7050 5750);
DOT 1 (-7050 5700);
DOT 1 (-6475 6150);
DOT 1 (-5025 6250);
DOT 1 (-4400 5975);
DOT 1 (-2950 6075);
DOT 1 (-2325 6100);
DOT 1 (-5025 5600);
DOT 1 (-8500 500);
DOT 1 (-8500 550);
DOT 1 (-8500 600);
DOT 1 (-8500 650);
DOT 1 (-8500 700);
DOT 1 (-8500 750);
DOT 1 (-8500 800);
DOT 1 (-8500 850);
DOT 1 (-8500 900);
DOT 1 (-8500 950);
DOT 1 (-8500 1000);
DOT 1 (-8500 1050);
DOT 1 (-8500 1100);
DOT 1 (-8500 1150);
DOT 1 (-8500 1200);
DOT 1 (-8500 1250);
DOT 1 (-8500 1300);
DOT 1 (-8500 1350);
DOT 1 (-8500 1400);
DOT 1 (-8500 1450);
DOT 1 (-8500 1500);
DOT 1 (-8500 1550);
DOT 1 (-8500 1650);
DOT 1 (-8500 1750);
DOT 1 (-8500 1700);
DOT 1 (-8500 1800);
DOT 1 (-8500 1850);
DOT 1 (-8500 1900);
DOT 1 (-8500 1950);
DOT 1 (-8500 2000);
DOT 1 (-8500 2050);
DOT 1 (-8500 2100);
DOT 1 (-8500 2150);
DOT 1 (-8500 2200);
DOT 1 (-8500 2250);
DOT 1 (-8500 2300);
DOT 1 (-8500 2350);
DOT 1 (-8500 2400);
DOT 1 (-8500 2450);
DOT 1 (-8500 2500);
DOT 1 (-8500 2550);
DOT 1 (-8500 2600);
DOT 1 (-8500 2650);
DOT 1 (-8500 2700);
DOT 1 (-8500 2750);
DOT 1 (-8500 2800);
DOT 1 (-8500 2850);
DOT 1 (-8500 2900);
DOT 1 (-8500 2950);
DOT 1 (-8500 3000);
DOT 1 (-8500 3050);
DOT 1 (-8500 3100);
DOT 1 (-8500 3200);
DOT 1 (-8500 3150);
DOT 1 (-8500 3250);
DOT 1 (-8500 3300);
DOT 1 (-8500 3350);
DOT 1 (-8500 3400);
DOT 1 (-8500 3450);
DOT 1 (-8500 3550);
DOT 1 (-8500 3500);
DOT 1 (-8500 3600);
DOT 1 (-8500 3650);
DOT 1 (-8500 3700);
DOT 1 (-8500 3750);
DOT 1 (-8500 3800);
DOT 1 (-8500 3850);
DOT 1 (-8500 3900);
DOT 1 (-8500 3950);
DOT 1 (-8500 4000);
DOT 1 (-8500 4050);
DOT 1 (-8500 4100);
DOT 1 (-8500 4150);
DOT 1 (-8500 4200);
DOT 1 (-8500 4250);
DOT 1 (-8500 4300);
DOT 1 (-8500 4350);
DOT 1 (-8500 4400);
DOT 1 (-8500 4450);
DOT 1 (-8500 4500);
DOT 1 (-8500 4550);
DOT 1 (-8500 4600);
DOT 1 (-8500 4650);
DOT 1 (-8500 4700);
DOT 1 (-8500 4750);
DOT 1 (-8500 4800);
DOT 1 (-8500 4850);
DOT 1 (-8500 4950);
DOT 1 (-8500 5000);
DOT 1 (-8500 5050);
DOT 1 (-8500 5100);
DOT 1 (-8500 5150);
DOT 1 (-8500 5200);
DOT 1 (-8500 5250);
DOT 1 (-8500 5300);
DOT 1 (-8500 5350);
DOT 1 (-8500 5400);
DOT 1 (-8500 5450);
DOT 1 (-8500 5500);
DOT 1 (-8500 5550);
DOT 1 (-8500 5600);
DOT 1 (-8500 5650);
DOT 1 (-8500 5700);
DOT 1 (-8500 5750);
DOT 1 (-8500 5800);
DOT 1 (-8500 5850);
DOT 1 (-8500 5900);
DOT 1 (-8500 5950);
DOT 1 (-8500 6000);
DOT 1 (-8500 6050);
DOT 1 (-8500 6100);
DOT 1 (-8500 6150);
DOT 1 (-8500 6200);
DOT 1 (-8500 6250);
DOT 1 (-8500 6300);
DOT 1 (-8500 6350);
DOT 1 (-7050 600);
DOT 1 (-7050 550);
DOT 1 (-7050 650);
DOT 1 (-7050 750);
DOT 1 (-7050 700);
DOT 1 (-7050 850);
DOT 1 (-7050 800);
DOT 1 (-7050 900);
DOT 1 (-7050 1000);
DOT 1 (-7050 950);
DOT 1 (-6475 500);
DOT 1 (-6475 550);
DOT 1 (-6475 600);
DOT 1 (-6475 650);
DOT 1 (-6475 700);
DOT 1 (-6475 750);
DOT 1 (-6475 800);
DOT 1 (-6475 850);
DOT 1 (-6475 900);
DOT 1 (-6475 1000);
DOT 1 (-6475 950);
DOT 1 (-7050 1050);
DOT 1 (-7050 1100);
DOT 1 (-7050 1150);
DOT 1 (-7050 1200);
DOT 1 (-7050 1250);
DOT 1 (-7050 1350);
DOT 1 (-7050 1400);
DOT 1 (-7050 1300);
DOT 1 (-7050 1450);
DOT 1 (-7050 1500);
DOT 1 (-7050 1550);
DOT 1 (-7050 1600);
DOT 1 (-7050 1650);
DOT 1 (-7050 1700);
DOT 1 (-7050 1750);
DOT 1 (-7050 1800);
DOT 1 (-7050 1900);
DOT 1 (-7050 1850);
DOT 1 (-7050 1950);
DOT 1 (-7050 2000);
DOT 1 (-6475 1050);
DOT 1 (-6475 1100);
DOT 1 (-6475 1150);
DOT 1 (-6475 1200);
DOT 1 (-6475 1250);
DOT 1 (-6475 1300);
DOT 1 (-6475 1350);
DOT 1 (-6475 1400);
DOT 1 (-6475 1450);
DOT 1 (-6475 1500);
DOT 1 (-6475 1550);
DOT 1 (-6475 1600);
DOT 1 (-6475 1650);
DOT 1 (-6475 1700);
DOT 1 (-6475 1750);
DOT 1 (-6475 1800);
DOT 1 (-6475 1850);
DOT 1 (-6475 1900);
DOT 1 (-6475 1950);
DOT 1 (-6475 2000);
DOT 1 (-7050 2050);
DOT 1 (-6475 2050);
DOT 1 (-7050 2150);
DOT 1 (-7050 2100);
DOT 1 (-7050 2300);
DOT 1 (-7050 2250);
DOT 1 (-7050 2200);
DOT 1 (-7050 2400);
DOT 1 (-7050 2350);
DOT 1 (-7050 2550);
DOT 1 (-7050 2500);
DOT 1 (-7050 2450);
DOT 1 (-7050 2650);
DOT 1 (-7050 2600);
DOT 1 (-7050 2700);
DOT 1 (-7050 2800);
DOT 1 (-7050 2750);
DOT 1 (-7050 2900);
DOT 1 (-7050 2850);
DOT 1 (-7050 2950);
DOT 1 (-7050 3050);
DOT 1 (-7050 3000);
DOT 1 (-6475 2100);
DOT 1 (-6475 2150);
DOT 1 (-6475 2200);
DOT 1 (-6475 2250);
DOT 1 (-6475 2300);
DOT 1 (-6475 2350);
DOT 1 (-6475 2400);
DOT 1 (-6475 2500);
DOT 1 (-6475 2450);
DOT 1 (-6475 2550);
DOT 1 (-6475 2600);
DOT 1 (-6475 2650);
DOT 1 (-6475 2700);
DOT 1 (-6475 2750);
DOT 1 (-6475 2800);
DOT 1 (-6475 2850);
DOT 1 (-6475 2900);
DOT 1 (-6475 2950);
DOT 1 (-6475 3050);
DOT 1 (-6475 3000);
DOT 1 (-7050 3100);
DOT 1 (-7050 3150);
DOT 1 (-7050 3200);
DOT 1 (-7050 3250);
DOT 1 (-7050 3300);
DOT 1 (-7050 3400);
DOT 1 (-7050 3450);
DOT 1 (-7050 3350);
DOT 1 (-7050 3500);
DOT 1 (-7050 3550);
DOT 1 (-7050 3650);
DOT 1 (-7050 3700);
DOT 1 (-7050 3600);
DOT 1 (-7050 3750);
DOT 1 (-7050 3800);
DOT 1 (-7050 3850);
DOT 1 (-7050 3950);
DOT 1 (-7050 3900);
DOT 1 (-7050 4000);
DOT 1 (-7050 4050);
DOT 1 (-6475 3100);
DOT 1 (-6475 3150);
DOT 1 (-6475 3200);
DOT 1 (-6475 3250);
DOT 1 (-6475 3300);
DOT 1 (-6475 3350);
DOT 1 (-6475 3400);
DOT 1 (-6475 3450);
DOT 1 (-6475 3550);
DOT 1 (-6475 3600);
DOT 1 (-6475 3650);
DOT 1 (-6475 3700);
DOT 1 (-6475 3750);
DOT 1 (-6475 3800);
DOT 1 (-6475 3850);
DOT 1 (-6475 3900);
DOT 1 (-6475 3950);
DOT 1 (-6475 4000);
DOT 1 (-6475 4050);
DOT 1 (-5025 500);
DOT 1 (-5025 600);
DOT 1 (-5025 550);
DOT 1 (-5025 650);
DOT 1 (-5025 700);
DOT 1 (-5025 750);
DOT 1 (-5025 800);
DOT 1 (-5025 850);
DOT 1 (-5025 900);
DOT 1 (-5025 950);
DOT 1 (-5025 1000);
DOT 1 (-4400 625);
DOT 1 (-4400 575);
DOT 1 (-4400 675);
DOT 1 (-4400 725);
DOT 1 (-4400 775);
DOT 1 (-4400 825);
DOT 1 (-4400 875);
DOT 1 (-4400 925);
DOT 1 (-4400 975);
DOT 1 (-4400 1025);
DOT 1 (-5025 1050);
DOT 1 (-5025 1100);
DOT 1 (-5025 1150);
DOT 1 (-5025 1200);
DOT 1 (-5025 1250);
DOT 1 (-5025 1300);
DOT 1 (-5025 1350);
DOT 1 (-5025 1400);
DOT 1 (-5025 1450);
DOT 1 (-5025 1500);
DOT 1 (-5025 1550);
DOT 1 (-5025 1600);
DOT 1 (-5025 1650);
DOT 1 (-5025 1700);
DOT 1 (-5025 1750);
DOT 1 (-5025 1800);
DOT 1 (-5025 1850);
DOT 1 (-5025 1900);
DOT 1 (-5025 1950);
DOT 1 (-5025 2000);
DOT 1 (-4400 1075);
DOT 1 (-4400 1125);
DOT 1 (-4400 1175);
DOT 1 (-4400 1225);
DOT 1 (-4400 1275);
DOT 1 (-4400 1325);
DOT 1 (-4400 1375);
DOT 1 (-4400 1425);
DOT 1 (-4400 1475);
DOT 1 (-4400 1525);
DOT 1 (-4400 1575);
DOT 1 (-4400 1625);
DOT 1 (-4400 1675);
DOT 1 (-4400 1725);
DOT 1 (-4400 1775);
DOT 1 (-4400 1875);
DOT 1 (-4400 1825);
DOT 1 (-4400 1925);
DOT 1 (-4400 1975);
DOT 1 (-4400 2025);
DOT 1 (-5025 2050);
DOT 1 (-5025 2100);
DOT 1 (-5025 2150);
DOT 1 (-5025 2200);
DOT 1 (-5025 2250);
DOT 1 (-5025 2300);
DOT 1 (-5025 2350);
DOT 1 (-5025 2400);
DOT 1 (-5025 2450);
DOT 1 (-5025 2500);
DOT 1 (-5025 2550);
DOT 1 (-5025 2600);
DOT 1 (-5025 2650);
DOT 1 (-5025 2700);
DOT 1 (-5025 2750);
DOT 1 (-5025 2800);
DOT 1 (-5025 2850);
DOT 1 (-5025 2900);
DOT 1 (-5025 2950);
DOT 1 (-5025 3000);
DOT 1 (-5025 3050);
DOT 1 (-4400 2075);
DOT 1 (-4400 2125);
DOT 1 (-4400 2175);
DOT 1 (-4400 2225);
DOT 1 (-4400 2275);
DOT 1 (-4400 2325);
DOT 1 (-4400 2375);
DOT 1 (-4400 2425);
DOT 1 (-4400 2475);
DOT 1 (-4400 2525);
DOT 1 (-4400 2575);
DOT 1 (-4400 2625);
DOT 1 (-4400 2675);
DOT 1 (-4400 2725);
DOT 1 (-4400 2775);
DOT 1 (-4400 2825);
DOT 1 (-4400 2875);
DOT 1 (-4400 2925);
DOT 1 (-4400 2975);
DOT 1 (-4400 3025);
DOT 1 (-4400 3075);
DOT 1 (-5025 3100);
DOT 1 (-5025 3200);
DOT 1 (-5025 3150);
DOT 1 (-5025 3300);
DOT 1 (-5025 3250);
DOT 1 (-5025 3350);
DOT 1 (-5025 3400);
DOT 1 (-5025 3450);
DOT 1 (-5025 3550);
DOT 1 (-5025 3500);
DOT 1 (-5025 3600);
DOT 1 (-5025 3650);
DOT 1 (-5025 3700);
DOT 1 (-5025 3750);
DOT 1 (-5025 3800);
DOT 1 (-5025 3850);
DOT 1 (-5025 3900);
DOT 1 (-5025 3950);
DOT 1 (-5025 4050);
DOT 1 (-5025 4000);
DOT 1 (-4400 3125);
DOT 1 (-4400 3175);
DOT 1 (-4400 3225);
DOT 1 (-4400 3275);
DOT 1 (-4400 3325);
DOT 1 (-4400 3375);
DOT 1 (-4400 3425);
DOT 1 (-4400 3475);
DOT 1 (-4400 3525);
DOT 1 (-4400 3575);
DOT 1 (-4400 3625);
DOT 1 (-4400 3675);
DOT 1 (-4400 3725);
DOT 1 (-4400 3775);
DOT 1 (-4400 3825);
DOT 1 (-4400 3875);
DOT 1 (-4400 3925);
DOT 1 (-4400 3975);
DOT 1 (-4400 4025);
DOT 1 (-4400 4075);
DOT 1 (-7050 4100);
DOT 1 (-6475 4100);
DOT 1 (-5025 4100);
DOT 1 (-7050 4200);
DOT 1 (-7050 4150);
DOT 1 (-7050 4300);
DOT 1 (-7050 4350);
DOT 1 (-7050 4250);
DOT 1 (-7050 4450);
DOT 1 (-7050 4400);
DOT 1 (-7050 4550);
DOT 1 (-7050 4600);
DOT 1 (-7050 4500);
DOT 1 (-7050 4650);
DOT 1 (-7050 4700);
DOT 1 (-7050 4750);
DOT 1 (-7050 4800);
DOT 1 (-7050 4850);
DOT 1 (-7050 4950);
DOT 1 (-7050 4900);
DOT 1 (-7050 5000);
DOT 1 (-7050 5100);
DOT 1 (-7050 5050);
DOT 1 (-6475 4200);
DOT 1 (-6475 4250);
DOT 1 (-6475 4300);
DOT 1 (-6475 4350);
DOT 1 (-6475 4400);
DOT 1 (-6475 4450);
DOT 1 (-6475 4550);
DOT 1 (-6475 4500);
DOT 1 (-6475 4600);
DOT 1 (-6475 4650);
DOT 1 (-6475 4700);
DOT 1 (-6475 4750);
DOT 1 (-6475 4800);
DOT 1 (-6475 4850);
DOT 1 (-6475 4900);
DOT 1 (-6475 4950);
DOT 1 (-6475 5000);
DOT 1 (-6475 5100);
DOT 1 (-6475 5050);
DOT 1 (-7050 5200);
DOT 1 (-7050 5150);
DOT 1 (-7050 5250);
DOT 1 (-7050 5350);
DOT 1 (-7050 5300);
DOT 1 (-7050 5450);
DOT 1 (-7050 5500);
DOT 1 (-7050 5400);
DOT 1 (-7050 5550);
DOT 1 (-7050 5600);
DOT 1 (-7050 5650);
DOT 1 (-7050 5800);
DOT 1 (-7050 5850);
DOT 1 (-7050 5900);
DOT 1 (-7050 6000);
DOT 1 (-7050 5950);
DOT 1 (-7050 6050);
DOT 1 (-7050 6100);
DOT 1 (-6475 5150);
DOT 1 (-6475 5200);
DOT 1 (-6475 5250);
DOT 1 (-6475 5300);
DOT 1 (-6475 5350);
DOT 1 (-6475 5400);
DOT 1 (-6475 5450);
DOT 1 (-6475 5500);
DOT 1 (-6475 5550);
DOT 1 (-6475 5600);
DOT 1 (-6475 5650);
DOT 1 (-6475 5700);
DOT 1 (-6475 5750);
DOT 1 (-6475 5800);
DOT 1 (-6475 5850);
DOT 1 (-6475 5900);
DOT 1 (-6475 5950);
DOT 1 (-6475 6000);
DOT 1 (-6475 6050);
DOT 1 (-6475 6100);
DOT 1 (-7050 6150);
DOT 1 (-7050 6250);
DOT 1 (-7050 6200);
DOT 1 (-7050 6350);
DOT 1 (-7050 6300);
DOT 1 (-6475 6250);
DOT 1 (-6475 6200);
DOT 1 (-6475 6300);
DOT 1 (-5025 4150);
DOT 1 (-5025 4200);
DOT 1 (-5025 4250);
DOT 1 (-5025 4300);
DOT 1 (-5025 4350);
DOT 1 (-5025 4450);
DOT 1 (-5025 4400);
DOT 1 (-5025 4500);
DOT 1 (-5025 4550);
DOT 1 (-5025 4600);
DOT 1 (-5025 4650);
DOT 1 (-5025 4700);
DOT 1 (-5025 4750);
DOT 1 (-5025 4800);
DOT 1 (-5025 4850);
DOT 1 (-5025 4900);
DOT 1 (-5025 4950);
DOT 1 (-5025 5000);
DOT 1 (-5025 5050);
DOT 1 (-5025 5100);
DOT 1 (-4400 4125);
DOT 1 (-4400 4175);
DOT 1 (-4400 4225);
DOT 1 (-4400 4275);
DOT 1 (-4400 4325);
DOT 1 (-4400 4375);
DOT 1 (-4400 4425);
DOT 1 (-4400 4475);
DOT 1 (-4400 4575);
DOT 1 (-4400 4525);
DOT 1 (-4400 4625);
DOT 1 (-4400 4675);
DOT 1 (-4400 4725);
DOT 1 (-4400 4775);
DOT 1 (-4400 4825);
DOT 1 (-4400 4875);
DOT 1 (-4400 4925);
DOT 1 (-4400 4975);
DOT 1 (-4400 5025);
DOT 1 (-4400 5075);
DOT 1 (-4400 5125);
DOT 1 (-5025 5150);
DOT 1 (-5025 5200);
DOT 1 (-5025 5250);
DOT 1 (-5025 5300);
DOT 1 (-5025 5350);
DOT 1 (-5025 5400);
DOT 1 (-5025 5450);
DOT 1 (-5025 5500);
DOT 1 (-5025 5550);
DOT 1 (-5025 5650);
DOT 1 (-5025 5700);
DOT 1 (-5025 5750);
DOT 1 (-5025 5800);
DOT 1 (-5025 5850);
DOT 1 (-5025 5900);
DOT 1 (-5025 5950);
DOT 1 (-5025 6000);
DOT 1 (-5025 6050);
DOT 1 (-5025 6100);
DOT 1 (-4400 5175);
DOT 1 (-4400 5225);
DOT 1 (-4400 5275);
DOT 1 (-4400 5325);
DOT 1 (-4400 5375);
DOT 1 (-4400 5425);
DOT 1 (-4400 5475);
DOT 1 (-4400 5525);
DOT 1 (-4400 5575);
DOT 1 (-4400 5625);
DOT 1 (-4400 5675);
DOT 1 (-4400 5725);
DOT 1 (-4400 5775);
DOT 1 (-4400 5825);
DOT 1 (-4400 5875);
DOT 1 (-4400 5925);
DOT 1 (-4400 6025);
DOT 1 (-4400 6075);
DOT 1 (-4400 6125);
DOT 1 (-5025 6150);
DOT 1 (-5025 6200);
DOT 1 (-4400 6175);
DOT 1 (-4400 6225);
DOT 1 (-2950 575);
DOT 1 (-2950 625);
DOT 1 (-2950 725);
DOT 1 (-2950 675);
DOT 1 (-2950 775);
DOT 1 (-2950 875);
DOT 1 (-2950 825);
DOT 1 (-2950 975);
DOT 1 (-2950 925);
DOT 1 (-2325 500);
DOT 1 (-2325 550);
DOT 1 (-2325 600);
DOT 1 (-2325 650);
DOT 1 (-2325 700);
DOT 1 (-2325 750);
DOT 1 (-2325 800);
DOT 1 (-2325 850);
DOT 1 (-2325 900);
DOT 1 (-2325 950);
DOT 1 (-2325 1000);
DOT 1 (-2950 1025);
DOT 1 (-2950 1125);
DOT 1 (-2950 1075);
DOT 1 (-2950 1275);
DOT 1 (-2950 1225);
DOT 1 (-2950 1175);
DOT 1 (-2950 1375);
DOT 1 (-2950 1325);
DOT 1 (-2950 1525);
DOT 1 (-2950 1475);
DOT 1 (-2950 1425);
DOT 1 (-2950 1575);
DOT 1 (-2950 1625);
DOT 1 (-2950 1675);
DOT 1 (-2950 1775);
DOT 1 (-2950 1725);
DOT 1 (-2950 1875);
DOT 1 (-2950 1825);
DOT 1 (-2950 1925);
DOT 1 (-2950 2025);
DOT 1 (-2950 1975);
DOT 1 (-2325 1050);
DOT 1 (-2325 1100);
DOT 1 (-2325 1150);
DOT 1 (-2325 1200);
DOT 1 (-2325 1250);
DOT 1 (-2325 1300);
DOT 1 (-2325 1350);
DOT 1 (-2325 1400);
DOT 1 (-2325 1450);
DOT 1 (-2325 1500);
DOT 1 (-2325 1550);
DOT 1 (-2325 1600);
DOT 1 (-2325 1650);
DOT 1 (-2325 1700);
DOT 1 (-2325 1750);
DOT 1 (-2325 1800);
DOT 1 (-2325 1850);
DOT 1 (-2325 1900);
DOT 1 (-2325 1950);
DOT 1 (-2325 2000);
DOT 1 (-2325 2050);
DOT 1 (-2950 2175);
DOT 1 (-2950 2125);
DOT 1 (-2950 2075);
DOT 1 (-2950 2275);
DOT 1 (-2950 2225);
DOT 1 (-2950 2375);
DOT 1 (-2950 2425);
DOT 1 (-2950 2325);
DOT 1 (-2950 2525);
DOT 1 (-2950 2475);
DOT 1 (-2950 2625);
DOT 1 (-2950 2675);
DOT 1 (-2950 2575);
DOT 1 (-2950 2725);
DOT 1 (-2950 2775);
DOT 1 (-2950 2825);
DOT 1 (-2950 2925);
DOT 1 (-2950 2875);
DOT 1 (-2950 2975);
DOT 1 (-2950 3025);
DOT 1 (-2325 2100);
DOT 1 (-2325 2150);
DOT 1 (-2325 2200);
DOT 1 (-2325 2250);
DOT 1 (-2325 2300);
DOT 1 (-2325 2350);
DOT 1 (-2325 2400);
DOT 1 (-2325 2450);
DOT 1 (-2325 2500);
DOT 1 (-2325 2550);
DOT 1 (-2325 2650);
DOT 1 (-2325 2600);
DOT 1 (-2325 2700);
DOT 1 (-2325 2750);
DOT 1 (-2325 2800);
DOT 1 (-2325 2850);
DOT 1 (-2325 2900);
DOT 1 (-2325 2950);
DOT 1 (-2325 3000);
DOT 1 (-2325 3050);
DOT 1 (-2950 3075);
DOT 1 (-2950 3175);
DOT 1 (-2950 3125);
DOT 1 (-2950 3325);
DOT 1 (-2950 3275);
DOT 1 (-2950 3225);
DOT 1 (-2950 3375);
DOT 1 (-2950 3425);
DOT 1 (-2950 3575);
DOT 1 (-2950 3525);
DOT 1 (-2950 3475);
DOT 1 (-2950 3625);
DOT 1 (-2950 3675);
DOT 1 (-2950 3725);
DOT 1 (-2950 3825);
DOT 1 (-2950 3775);
DOT 1 (-2950 3925);
DOT 1 (-2950 3875);
DOT 1 (-2950 3975);
DOT 1 (-2950 4075);
DOT 1 (-2950 4025);
DOT 1 (-2325 3100);
DOT 1 (-2325 3150);
DOT 1 (-2325 3200);
DOT 1 (-2325 3250);
DOT 1 (-2325 3300);
DOT 1 (-2325 3350);
DOT 1 (-2325 3400);
DOT 1 (-2325 3450);
DOT 1 (-2325 3500);
DOT 1 (-2325 3550);
DOT 1 (-2325 3600);
DOT 1 (-2325 3650);
DOT 1 (-2325 3700);
DOT 1 (-2325 3750);
DOT 1 (-2325 3800);
DOT 1 (-2325 3850);
DOT 1 (-2325 3900);
DOT 1 (-2325 3950);
DOT 1 (-2325 4000);
DOT 1 (-2325 4050);
DOT 1 (-875 500);
DOT 1 (-875 600);
DOT 1 (-875 550);
DOT 1 (-875 650);
DOT 1 (-875 700);
DOT 1 (-875 750);
DOT 1 (-875 850);
DOT 1 (-875 800);
DOT 1 (-875 900);
DOT 1 (-875 950);
DOT 1 (-875 1000);
DOT 1 (-875 1050);
DOT 1 (-875 1100);
DOT 1 (-875 1150);
DOT 1 (-875 1250);
DOT 1 (-875 1200);
DOT 1 (-875 1300);
DOT 1 (-875 1350);
DOT 1 (-875 1400);
DOT 1 (-875 1500);
DOT 1 (-875 1450);
DOT 1 (-875 1600);
DOT 1 (-875 1550);
DOT 1 (-875 1650);
DOT 1 (-875 1750);
DOT 1 (-875 1700);
DOT 1 (-875 1800);
DOT 1 (-875 1850);
DOT 1 (-875 1900);
DOT 1 (-875 2000);
DOT 1 (-875 1950);
DOT 1 (-875 2050);
DOT 1 (-875 2100);
DOT 1 (-875 2150);
DOT 1 (-875 2200);
DOT 1 (-875 2250);
DOT 1 (-875 2300);
DOT 1 (-875 2400);
DOT 1 (-875 2350);
DOT 1 (-875 2450);
DOT 1 (-875 2500);
DOT 1 (-875 2550);
DOT 1 (-875 2650);
DOT 1 (-875 2600);
DOT 1 (-875 2700);
DOT 1 (-875 2750);
DOT 1 (-875 2800);
DOT 1 (-875 2900);
DOT 1 (-875 2850);
DOT 1 (-875 2950);
DOT 1 (-875 3000);
DOT 1 (-875 3050);
DOT 1 (-875 3100);
DOT 1 (-875 3150);
DOT 1 (-875 3200);
DOT 1 (-875 3250);
DOT 1 (-875 3300);
DOT 1 (-875 3350);
DOT 1 (-875 3400);
DOT 1 (-875 3450);
DOT 1 (-875 3500);
DOT 1 (-875 3550);
DOT 1 (-875 3600);
DOT 1 (-875 3650);
DOT 1 (-875 3700);
DOT 1 (-875 3800);
DOT 1 (-875 3750);
DOT 1 (-875 3850);
DOT 1 (-875 3900);
DOT 1 (-875 3950);
DOT 1 (-875 4050);
DOT 1 (-875 4000);
DOT 1 (-2325 4100);
DOT 1 (-875 4100);
DOT 1 (-2950 4175);
DOT 1 (-2950 4125);
DOT 1 (-2950 4225);
DOT 1 (-2950 4325);
DOT 1 (-2950 4275);
DOT 1 (-2950 4475);
DOT 1 (-2950 4425);
DOT 1 (-2950 4375);
DOT 1 (-2950 4525);
DOT 1 (-2950 4575);
DOT 1 (-2950 4675);
DOT 1 (-2950 4725);
DOT 1 (-2950 4625);
DOT 1 (-2950 4825);
DOT 1 (-2950 4775);
DOT 1 (-2950 4875);
DOT 1 (-2950 4975);
DOT 1 (-2950 4925);
DOT 1 (-2950 5025);
DOT 1 (-2950 5075);
DOT 1 (-2325 4150);
DOT 1 (-2325 4200);
DOT 1 (-2325 4250);
DOT 1 (-2325 4300);
DOT 1 (-2325 4350);
DOT 1 (-2325 4400);
DOT 1 (-2325 4450);
DOT 1 (-2325 4500);
DOT 1 (-2325 4550);
DOT 1 (-2325 4600);
DOT 1 (-2325 4700);
DOT 1 (-2325 4650);
DOT 1 (-2325 4750);
DOT 1 (-2325 4800);
DOT 1 (-2325 4850);
DOT 1 (-2325 4900);
DOT 1 (-2325 4950);
DOT 1 (-2325 5000);
DOT 1 (-2325 5050);
DOT 1 (-2325 5100);
DOT 1 (-2950 5125);
DOT 1 (-2950 5225);
DOT 1 (-2950 5175);
DOT 1 (-2950 5375);
DOT 1 (-2950 5325);
DOT 1 (-2950 5275);
DOT 1 (-2950 5425);
DOT 1 (-2950 5475);
DOT 1 (-2950 5625);
DOT 1 (-2950 5575);
DOT 1 (-2950 5525);
DOT 1 (-2950 5675);
DOT 1 (-2950 5725);
DOT 1 (-2950 5875);
DOT 1 (-2950 5825);
DOT 1 (-2950 5775);
DOT 1 (-2950 5975);
DOT 1 (-2950 5925);
DOT 1 (-2950 6025);
DOT 1 (-2950 6125);
DOT 1 (-2325 5200);
DOT 1 (-2325 5150);
DOT 1 (-2325 5250);
DOT 1 (-2325 5300);
DOT 1 (-2325 5350);
DOT 1 (-2325 5400);
DOT 1 (-2325 5450);
DOT 1 (-2325 5500);
DOT 1 (-2325 5550);
DOT 1 (-2325 5600);
DOT 1 (-2325 5650);
DOT 1 (-2325 5700);
DOT 1 (-2325 5750);
DOT 1 (-2325 5800);
DOT 1 (-2325 5850);
DOT 1 (-2325 5900);
DOT 1 (-2325 5950);
DOT 1 (-2325 6000);
DOT 1 (-2325 6050);
DOT 1 (-2325 6150);
DOT 1 (-2950 6175);
DOT 1 (-2950 6225);
DOT 1 (-2950 6275);
DOT 1 (-2950 6325);
DOT 1 (-2325 6200);
DOT 1 (-2325 6250);
DOT 1 (-875 4150);
DOT 1 (-875 4200);
DOT 1 (-875 4250);
DOT 1 (-875 4300);
DOT 1 (-875 4350);
DOT 1 (-875 4400);
DOT 1 (-875 4450);
DOT 1 (-875 4500);
DOT 1 (-875 4550);
DOT 1 (-875 4600);
DOT 1 (-875 4700);
DOT 1 (-875 4650);
DOT 1 (-875 4800);
DOT 1 (-875 4750);
DOT 1 (-875 4850);
DOT 1 (-875 4950);
DOT 1 (-875 4900);
DOT 1 (-875 5000);
DOT 1 (-875 5050);
DOT 1 (-875 5100);
DOT 1 (-875 5200);
DOT 1 (-875 5150);
DOT 1 (-875 5250);
DOT 1 (-875 5300);
DOT 1 (-875 5350);
DOT 1 (-875 5400);
DOT 1 (-875 5450);
DOT 1 (-875 5500);
DOT 1 (-875 5550);
DOT 1 (-875 5600);
DOT 1 (-875 5650);
DOT 1 (-875 5700);
DOT 1 (-875 5750);
DOT 1 (-875 5850);
DOT 1 (-875 5800);
DOT 1 (-875 5900);
DOT 1 (-875 5950);
DOT 1 (-875 6000);
DOT 1 (-875 6100);
DOT 1 (-875 6050);
DOT 1 (-875 6150);
DOT 1 (-875 6200);
DOT 1 (-875 6250);
DOT 1 (-8500 1600);
QUIT
